FILE_TYPE = MACRO_DRAWING;
SET COLOR_WIRE YELLOW;
SET COLOR_PROP ORANGE;
SET COLOR_DOT WHITE;
SET COLOR_ARC YELLOW;
SET COLOR_BODY GREEN;
SET COLOR_NOTE PURPLE;
SET PROP_DISPLAY VALUE;
SET PAGE_NUMBER P340;
FORCEADD OFFPAGE..1
(-1975 5325);
PAINT AQUA (-1975 5325);
FORCEPROP 2 LAST $XR0 82 
J 0
(-2196 5325);
DISPLAY 0.638298 (-2196 5325);
PAINT MONO (-2196 5325);
FORCEPROP 2 LAST CDS_LIB standard
J 0
(-1975 5325);
DISPLAY INVISIBLE (-1975 5325);
FORCEPROP 1 LAST OFFPAGE TRUE
J 0
(-1650 5200);
DISPLAY 0.872340 (-1650 5200);
PAINT AQUA (-1650 5200);
DISPLAY INVISIBLE (-1650 5200);
FORCEPROP 1 LAST COMMENT_BODY TRUE
J 0
(-1850 5225);
DISPLAY 0.872340 (-1850 5225);
PAINT GREEN (-1850 5225);
DISPLAY INVISIBLE (-1850 5225);
FORCEPROP 2 LAST PATH I1
J 0
(-2175 5375);
DISPLAY 0.680851 (-2175 5375);
DISPLAY INVISIBLE (-2175 5375);
FORCEADD OFFPAGE..1
(-5000 6475);
PAINT AQUA (-5000 6475);
FORCEPROP 2 LAST $XR1 136 
J 0
(-5372 6475);
DISPLAY 0.638298 (-5372 6475);
PAINT MONO (-5372 6475);
FORCEPROP 2 LAST $XR0 134 
J 0
(-5252 6475);
DISPLAY 0.638298 (-5252 6475);
PAINT MONO (-5252 6475);
FORCEPROP 2 LAST CDS_LIB standard
J 0
(-5000 6475);
DISPLAY INVISIBLE (-5000 6475);
FORCEPROP 1 LAST OFFPAGE TRUE
J 0
(-4675 6350);
DISPLAY 0.872340 (-4675 6350);
PAINT AQUA (-4675 6350);
DISPLAY INVISIBLE (-4675 6350);
FORCEPROP 1 LAST COMMENT_BODY TRUE
J 0
(-4875 6375);
DISPLAY 0.872340 (-4875 6375);
PAINT GREEN (-4875 6375);
DISPLAY INVISIBLE (-4875 6375);
FORCEPROP 2 LAST PATH I100
J 0
(-4950 6550);
DISPLAY 0.680851 (-4950 6550);
DISPLAY INVISIBLE (-4950 6550);
FORCEADD Q_RES..1
R 2
(-1950 6600);
FORCEPROP 1 LAST LOCATION R1519
J 2
(-2000 6525);
DISPLAY 0.617021 (-2000 6525);
PAINT SKYBLUE (-2000 6525);
FORCEPROP 0 LAST $SEC 1
J 0
(-2075 6675);
DISPLAY 0.680851 (-2075 6675);
PAINT MONO (-2075 6675);
DISPLAY INVISIBLE (-2075 6675);
FORCEPROP 0 LAST CDS_SEC 1
J 0
(-2075 6675);
DISPLAY 0.680851 (-2075 6675);
DISPLAY INVISIBLE (-2075 6675);
FORCEPROP 1 LASTPIN (-1850 6600) $PN 1
J 2
(-1862 6612);
DISPLAY 0.787234 (-1862 6612);
PAINT MONO (-1862 6612);
FORCEPROP 1 LASTPIN (-2050 6600) $PN 2
J 2
(-2012 6612);
DISPLAY 0.787234 (-2012 6612);
PAINT MONO (-2012 6612);
FORCEPROP 1 LAST MATERIAL EMPTY
J 0
(-2125 6575);
DISPLAY 0.489362 (-2125 6575);
PAINT RED (-2125 6575);
FORCEPROP 1 LAST VALUE 0
J 0
(-1875 6575);
DISPLAY 0.489362 (-1875 6575);
FORCEPROP 1 LAST WATTAGE 1/16W
J 0
(-1875 6525);
DISPLAY 0.489362 (-1875 6525);
PAINT SKYBLUE (-1875 6525);
DISPLAY INVISIBLE (-1875 6525);
FORCEPROP 1 LAST TOLERANCE 5%
J 2
(-1825 6575);
DISPLAY 0.489362 (-1825 6575);
PAINT SKYBLUE (-1825 6575);
DISPLAY INVISIBLE (-1825 6575);
FORCEPROP 1 LAST PACK_TYPE 0402LF
J 0
(-2125 6525);
DISPLAY 0.489362 (-2125 6525);
PAINT SKYBLUE (-2125 6525);
DISPLAY INVISIBLE (-2125 6525);
FORCEPROP 2 LAST CDS_LIB pure_quanta
J 0
(-1950 6600);
DISPLAY INVISIBLE (-1950 6600);
FORCEPROP 1 LAST PATH I101
J 2
(-1900 6750);
DISPLAY 0.978723 (-1900 6750);
PAINT WHITE (-1900 6750);
DISPLAY INVISIBLE (-1900 6750);
FORCEPROP 1 LAST PART_NUMBER CS00002JB13
J 0
(-2050 6650);
DISPLAY 0.489362 (-2050 6650);
PAINT SKYBLUE (-2050 6650);
DISPLAY INVISIBLE (-2050 6650);
FORCEADD Q_RES..1
(-2000 6325);
FORCEPROP 1 LAST LOCATION R1518
J 0
(-2050 6375);
DISPLAY 0.978723 (-2050 6375);
PAINT SKYBLUE (-2050 6375);
FORCEPROP 0 LAST $SEC 1
J 0
(-2050 6425);
DISPLAY 0.680851 (-2050 6425);
PAINT MONO (-2050 6425);
DISPLAY INVISIBLE (-2050 6425);
FORCEPROP 0 LAST CDS_SEC 1
J 0
(-2050 6425);
DISPLAY 0.680851 (-2050 6425);
DISPLAY INVISIBLE (-2050 6425);
FORCEPROP 1 LASTPIN (-2100 6325) $PN 1
J 0
(-2088 6337);
DISPLAY 0.787234 (-2088 6337);
PAINT MONO (-2088 6337);
FORCEPROP 1 LASTPIN (-1900 6325) $PN 2
J 0
(-1938 6337);
DISPLAY 0.787234 (-1938 6337);
PAINT MONO (-1938 6337);
FORCEPROP 1 LAST WATTAGE 1/16W
J 2
(-1800 6250);
DISPLAY 0.510638 (-1800 6250);
FORCEPROP 1 LAST PACK_TYPE 0402LF
J 0
(-1750 6325);
DISPLAY 0.510638 (-1750 6325);
FORCEPROP 1 LAST TOLERANCE 5%
J 0
(-1825 6325);
DISPLAY 0.510638 (-1825 6325);
FORCEPROP 1 LAST VALUE 0
J 2
(-1850 6325);
DISPLAY 0.510638 (-1850 6325);
FORCEPROP 1 LAST MATERIAL CHIP
J 0
(-2075 6250);
DISPLAY 0.510638 (-2075 6250);
PAINT RED (-2075 6250);
FORCEPROP 2 LAST CDS_LIB pure_quanta
J 0
(-2000 6325);
DISPLAY INVISIBLE (-2000 6325);
FORCEPROP 1 LAST PATH I102
J 0
(-2050 6475);
DISPLAY 0.978723 (-2050 6475);
PAINT WHITE (-2050 6475);
DISPLAY INVISIBLE (-2050 6475);
FORCEPROP 1 LAST PART_NUMBER CS00002JB13
J 0
(-2075 6275);
DISPLAY 0.510638 (-2075 6275);
DISPLAY INVISIBLE (-2075 6275);
FORCEADD OFFPAGE..1
(-1900 6700);
PAINT AQUA (-1900 6700);
FORCEPROP 2 LAST $XR0 81 
J 0
(-2151 6700);
DISPLAY 0.638298 (-2151 6700);
PAINT MONO (-2151 6700);
FORCEPROP 2 LAST CDS_LIB standard
J 0
(-1900 6700);
DISPLAY INVISIBLE (-1900 6700);
FORCEPROP 1 LAST OFFPAGE TRUE
J 0
(-1575 6575);
DISPLAY 0.872340 (-1575 6575);
PAINT AQUA (-1575 6575);
DISPLAY INVISIBLE (-1575 6575);
FORCEPROP 1 LAST COMMENT_BODY TRUE
J 0
(-1775 6600);
DISPLAY 0.872340 (-1775 6600);
PAINT GREEN (-1775 6600);
DISPLAY INVISIBLE (-1775 6600);
FORCEPROP 2 LAST PATH I12
J 0
(-2100 6750);
DISPLAY 0.680851 (-2100 6750);
DISPLAY INVISIBLE (-2100 6750);
FORCEADD Q_RES..1
(-1000 6600);
FORCEPROP 1 LAST LOCATION R9022
J 0
(-1200 6600);
DISPLAY 0.723404 (-1200 6600);
FORCEPROP 0 LAST $SEC 1
J 0
(-750 6650);
DISPLAY 0.680851 (-750 6650);
PAINT MONO (-750 6650);
DISPLAY INVISIBLE (-750 6650);
FORCEPROP 0 LAST CDS_SEC 1
J 0
(-750 6650);
DISPLAY 0.680851 (-750 6650);
DISPLAY INVISIBLE (-750 6650);
FORCEPROP 1 LASTPIN (-1100 6600) $PN 1
J 0
(-1088 6612);
DISPLAY 0.787234 (-1088 6612);
PAINT MONO (-1088 6612);
FORCEPROP 1 LASTPIN (-900 6600) $PN 2
J 0
(-938 6612);
DISPLAY 0.787234 (-938 6612);
PAINT MONO (-938 6612);
FORCEPROP 1 LAST VALUE 33.2
J 2
(-750 6600);
DISPLAY 0.723404 (-750 6600);
FORCEPROP 1 LAST MATERIAL CHIP
J 0
(-975 6550);
DISPLAY 0.723404 (-975 6550);
FORCEPROP 1 LAST PACK_TYPE 0402LF
J 0
(-1175 6550);
DISPLAY 0.723404 (-1175 6550);
FORCEPROP 1 LAST WATTAGE 1/16W
J 2
(-600 6550);
DISPLAY 0.723404 (-600 6550);
PAINT SKYBLUE (-600 6550);
DISPLAY INVISIBLE (-600 6550);
FORCEPROP 1 LAST TOLERANCE 1%
J 0
(-525 6600);
DISPLAY 0.723404 (-525 6600);
PAINT SKYBLUE (-525 6600);
DISPLAY INVISIBLE (-525 6600);
FORCEPROP 2 LAST CDS_LIB pure_quanta
J 0
(-1000 6600);
DISPLAY INVISIBLE (-1000 6600);
FORCEPROP 1 LAST PATH I13
J 0
(-1050 6750);
DISPLAY 0.978723 (-1050 6750);
PAINT WHITE (-1050 6750);
DISPLAY INVISIBLE (-1050 6750);
FORCEPROP 1 LAST PART_NUMBER CS03322FB03
J 0
(-1400 6500);
DISPLAY 0.723404 (-1400 6500);
PAINT WHITE (-1400 6500);
DISPLAY INVISIBLE (-1400 6500);
FORCEADD Q_RES..1
(-1000 6700);
FORCEPROP 1 LAST LOCATION R9023
J 0
(-1200 6700);
DISPLAY 0.723404 (-1200 6700);
FORCEPROP 0 LAST $SEC 1
J 0
(-750 6750);
DISPLAY 0.680851 (-750 6750);
PAINT MONO (-750 6750);
DISPLAY INVISIBLE (-750 6750);
FORCEPROP 0 LAST CDS_SEC 1
J 0
(-750 6750);
DISPLAY 0.680851 (-750 6750);
DISPLAY INVISIBLE (-750 6750);
FORCEPROP 1 LASTPIN (-1100 6700) $PN 1
J 0
(-1088 6712);
DISPLAY 0.787234 (-1088 6712);
PAINT MONO (-1088 6712);
FORCEPROP 1 LASTPIN (-900 6700) $PN 2
J 0
(-938 6712);
DISPLAY 0.787234 (-938 6712);
PAINT MONO (-938 6712);
FORCEPROP 1 LAST PACK_TYPE 0402LF
J 0
(-1175 6650);
DISPLAY 0.723404 (-1175 6650);
FORCEPROP 1 LAST MATERIAL CHIP
J 0
(-925 6650);
DISPLAY 0.723404 (-925 6650);
FORCEPROP 1 LAST VALUE 33.2
J 2
(-750 6700);
DISPLAY 0.723404 (-750 6700);
FORCEPROP 1 LAST TOLERANCE 1%
J 0
(-525 6700);
DISPLAY 0.723404 (-525 6700);
PAINT SKYBLUE (-525 6700);
DISPLAY INVISIBLE (-525 6700);
FORCEPROP 1 LAST WATTAGE 1/16W
J 2
(-600 6650);
DISPLAY 0.723404 (-600 6650);
PAINT SKYBLUE (-600 6650);
DISPLAY INVISIBLE (-600 6650);
FORCEPROP 2 LAST CDS_LIB pure_quanta
J 0
(-1000 6700);
DISPLAY INVISIBLE (-1000 6700);
FORCEPROP 1 LAST PATH I14
J 0
(-1050 6850);
DISPLAY 0.978723 (-1050 6850);
PAINT WHITE (-1050 6850);
DISPLAY INVISIBLE (-1050 6850);
FORCEPROP 1 LAST PART_NUMBER CS03322FB03
J 0
(-1400 6600);
DISPLAY 0.723404 (-1400 6600);
PAINT WHITE (-1400 6600);
DISPLAY INVISIBLE (-1400 6600);
FORCEADD Q_RES..1
R 2
(825 4575);
FORCEPROP 1 LAST LOCATION R9030
J 2
(1025 4575);
DISPLAY 0.489362 (1025 4575);
PAINT SKYBLUE (1025 4575);
FORCEPROP 0 LAST $SEC 1
J 0
(1025 4600);
DISPLAY 0.680851 (1025 4600);
PAINT MONO (1025 4600);
DISPLAY INVISIBLE (1025 4600);
FORCEPROP 0 LAST CDS_SEC 1
J 0
(1025 4600);
DISPLAY 0.680851 (1025 4600);
DISPLAY INVISIBLE (1025 4600);
FORCEPROP 1 LASTPIN (925 4575) $PN 1
J 2
(913 4587);
DISPLAY 0.787234 (913 4587);
PAINT MONO (913 4587);
FORCEPROP 1 LASTPIN (725 4575) $PN 2
J 2
(763 4587);
DISPLAY 0.787234 (763 4587);
PAINT MONO (763 4587);
FORCEPROP 1 LAST MATERIAL EMPTY
J 0
(650 4550);
DISPLAY 0.489362 (650 4550);
PAINT RED (650 4550);
FORCEPROP 1 LAST VALUE 0
J 0
(675 4575);
DISPLAY 0.489362 (675 4575);
PAINT SKYBLUE (675 4575);
FORCEPROP 2 LAST CDS_LIB pure_quanta
J 0
(825 4575);
DISPLAY INVISIBLE (825 4575);
FORCEPROP 2 LAST BOM_COST MEM
J 0
(800 4725);
DISPLAY 0.744681 (800 4725);
PAINT WHITE (800 4725);
DISPLAY INVISIBLE (800 4725);
FORCEPROP 1 LAST WATTAGE 1/16W
J 0
(900 4500);
DISPLAY 0.489362 (900 4500);
PAINT SKYBLUE (900 4500);
DISPLAY INVISIBLE (900 4500);
FORCEPROP 1 LAST TOLERANCE 5%
J 2
(950 4550);
DISPLAY 0.489362 (950 4550);
PAINT SKYBLUE (950 4550);
DISPLAY INVISIBLE (950 4550);
FORCEPROP 1 LAST PACK_TYPE 0402LF
J 0
(650 4500);
DISPLAY 0.489362 (650 4500);
PAINT SKYBLUE (650 4500);
DISPLAY INVISIBLE (650 4500);
FORCEPROP 1 LAST PATH I15
J 2
(875 4725);
DISPLAY 0.978723 (875 4725);
PAINT WHITE (875 4725);
DISPLAY INVISIBLE (875 4725);
FORCEPROP 1 LAST PART_NUMBER CS00002JB13
J 0
(725 4625);
DISPLAY 0.489362 (725 4625);
PAINT SKYBLUE (725 4625);
DISPLAY INVISIBLE (725 4625);
FORCEADD UNIVERSAL_GND..1
(150 5100);
FORCEPROP 3 LASTPIN (150 5150) SIG_NAME GND\g
J 0
(160 5160);
DISPLAY 0.659574 (160 5160);
PAINT MONO (160 5160);
DISPLAY INVISIBLE (160 5160);
FORCEPROP 2 LAST CDS_LIB pure_quanta_power
J 0
(150 5100);
DISPLAY INVISIBLE (150 5100);
FORCEPROP 1 LAST HDL_POWER GND
J 1
(175 5025);
DISPLAY 0.872340 (175 5025);
PAINT GREEN (175 5025);
DISPLAY INVISIBLE (175 5025);
FORCEPROP 1 LAST PATH I16
J 0
(225 5100);
DISPLAY 0.872340 (225 5100);
PAINT AQUA (225 5100);
DISPLAY INVISIBLE (225 5100);
FORCEADD Q_RES..1
R 2
(825 6075);
FORCEPROP 1 LAST LOCATION R9029
J 2
(1025 6075);
DISPLAY 0.489362 (1025 6075);
PAINT SKYBLUE (1025 6075);
FORCEPROP 0 LAST $SEC 1
J 0
(1025 6100);
DISPLAY 0.680851 (1025 6100);
PAINT MONO (1025 6100);
DISPLAY INVISIBLE (1025 6100);
FORCEPROP 0 LAST CDS_SEC 1
J 0
(1025 6100);
DISPLAY 0.680851 (1025 6100);
DISPLAY INVISIBLE (1025 6100);
FORCEPROP 1 LASTPIN (925 6075) $PN 1
J 2
(913 6087);
DISPLAY 0.787234 (913 6087);
PAINT MONO (913 6087);
FORCEPROP 1 LASTPIN (725 6075) $PN 2
J 2
(763 6087);
DISPLAY 0.787234 (763 6087);
PAINT MONO (763 6087);
FORCEPROP 1 LAST VALUE 0
J 0
(675 6075);
DISPLAY 0.489362 (675 6075);
PAINT SKYBLUE (675 6075);
FORCEPROP 1 LAST MATERIAL EMPTY
J 0
(650 6050);
DISPLAY 0.489362 (650 6050);
PAINT RED (650 6050);
FORCEPROP 1 LAST PACK_TYPE 0402LF
J 0
(650 6000);
DISPLAY 0.489362 (650 6000);
PAINT SKYBLUE (650 6000);
DISPLAY INVISIBLE (650 6000);
FORCEPROP 1 LAST TOLERANCE 5%
J 2
(950 6050);
DISPLAY 0.489362 (950 6050);
PAINT SKYBLUE (950 6050);
DISPLAY INVISIBLE (950 6050);
FORCEPROP 1 LAST WATTAGE 1/16W
J 0
(900 6000);
DISPLAY 0.489362 (900 6000);
PAINT SKYBLUE (900 6000);
DISPLAY INVISIBLE (900 6000);
FORCEPROP 2 LAST BOM_COST MEM
J 0
(800 6225);
DISPLAY 0.744681 (800 6225);
PAINT WHITE (800 6225);
DISPLAY INVISIBLE (800 6225);
FORCEPROP 2 LAST CDS_LIB pure_quanta
J 0
(825 6075);
DISPLAY INVISIBLE (825 6075);
FORCEPROP 1 LAST PATH I18
J 2
(875 6225);
DISPLAY 0.978723 (875 6225);
PAINT WHITE (875 6225);
DISPLAY INVISIBLE (875 6225);
FORCEPROP 1 LAST PART_NUMBER CS00002JB13
J 0
(725 6125);
DISPLAY 0.489362 (725 6125);
PAINT SKYBLUE (725 6125);
DISPLAY INVISIBLE (725 6125);
FORCEADD UNIVERSAL_GND..1
(-50 5500);
FORCEPROP 3 LASTPIN (-50 5550) SIG_NAME GND\g
J 0
(-40 5560);
DISPLAY 0.659574 (-40 5560);
PAINT MONO (-40 5560);
DISPLAY INVISIBLE (-40 5560);
FORCEPROP 2 LAST CDS_LIB pure_quanta_power
J 0
(-50 5500);
DISPLAY INVISIBLE (-50 5500);
FORCEPROP 1 LAST HDL_POWER GND
J 1
(-25 5425);
DISPLAY 0.872340 (-25 5425);
PAINT GREEN (-25 5425);
DISPLAY INVISIBLE (-25 5425);
FORCEPROP 1 LAST PATH I19
J 0
(25 5500);
DISPLAY 0.872340 (25 5500);
PAINT AQUA (25 5500);
DISPLAY INVISIBLE (25 5500);
FORCEADD Q_RES..2
R 2
(-1625 5650);
FORCEPROP 1 LAST LOCATION R9032
J 2
(-1670 5775);
DISPLAY 0.808511 (-1670 5775);
FORCEPROP 0 LAST $SEC 1
J 0
(-1650 5825);
DISPLAY 0.680851 (-1650 5825);
PAINT MONO (-1650 5825);
DISPLAY INVISIBLE (-1650 5825);
FORCEPROP 0 LAST CDS_SEC 1
J 0
(-1650 5825);
DISPLAY 0.680851 (-1650 5825);
DISPLAY INVISIBLE (-1650 5825);
FORCEPROP 1 LASTPIN (-1625 5750) $PN 1
J 2
(-1630 5712);
DISPLAY 0.787234 (-1630 5712);
PAINT MONO (-1630 5712);
FORCEPROP 1 LASTPIN (-1625 5550) $PN 2
J 2
(-1630 5560);
DISPLAY 0.787234 (-1630 5560);
PAINT MONO (-1630 5560);
FORCEPROP 1 LAST MATERIAL CHIP
J 2
(-1665 5575);
DISPLAY 0.638298 (-1665 5575);
FORCEPROP 1 LAST WATTAGE 1/16W
J 2
(-1665 5625);
DISPLAY 0.638298 (-1665 5625);
FORCEPROP 1 LAST PACK_TYPE 0402LF
J 2
(-1665 5475);
DISPLAY 0.638298 (-1665 5475);
FORCEPROP 1 LAST VALUE 10K
J 2
(-1670 5725);
DISPLAY 0.638298 (-1670 5725);
FORCEPROP 1 LAST TOLERANCE 1%
J 2
(-1670 5675);
DISPLAY 0.638298 (-1670 5675);
FORCEPROP 2 LAST CDS_LIB pure_quanta
J 0
(-1625 5650);
DISPLAY INVISIBLE (-1625 5650);
FORCEPROP 1 LAST PATH I2
J 2
(-1675 5825);
DISPLAY 0.978723 (-1675 5825);
PAINT WHITE (-1675 5825);
DISPLAY INVISIBLE (-1675 5825);
FORCEPROP 1 LAST PART_NUMBER CS31002FB08
J 2
(-1665 5525);
DISPLAY 0.638298 (-1665 5525);
DISPLAY INVISIBLE (-1665 5525);
FORCEADD UNIVERSAL_POWER..1
R 2
(-25 5925);
FORCEPROP 3 LASTPIN (-25 5875) SIG_NAME P3V3_AUX\g
J 0
(-15 5885);
DISPLAY 0.659574 (-15 5885);
PAINT MONO (-15 5885);
DISPLAY INVISIBLE (-15 5885);
FORCEPROP 1 LAST HDL_POWER P3V3_AUX
J 1
(-25 5975);
DISPLAY 0.723404 (-25 5975);
PAINT GREEN (-25 5975);
FORCEPROP 2 LAST CDS_LIB pure_quanta_power
J 0
(-25 5925);
DISPLAY INVISIBLE (-25 5925);
FORCEPROP 1 LAST PATH I21
J 2
(-75 5950);
DISPLAY 0.872340 (-75 5950);
PAINT AQUA (-75 5950);
DISPLAY INVISIBLE (-75 5950);
FORCEADD Q_RES..1
(1825 5375);
FORCEPROP 1 LAST LOCATION R9031
J 0
(1625 5375);
DISPLAY 0.723404 (1625 5375);
FORCEPROP 0 LAST $SEC 1
J 0
(2075 5425);
DISPLAY 0.680851 (2075 5425);
PAINT MONO (2075 5425);
DISPLAY INVISIBLE (2075 5425);
FORCEPROP 0 LAST CDS_SEC 1
J 0
(2075 5425);
DISPLAY 0.680851 (2075 5425);
DISPLAY INVISIBLE (2075 5425);
FORCEPROP 1 LASTPIN (1725 5375) $PN 1
J 0
(1737 5387);
DISPLAY 0.787234 (1737 5387);
PAINT MONO (1737 5387);
FORCEPROP 1 LASTPIN (1925 5375) $PN 2
J 0
(1887 5387);
DISPLAY 0.787234 (1887 5387);
PAINT MONO (1887 5387);
FORCEPROP 1 LAST PACK_TYPE 0402LF
J 0
(1650 5325);
DISPLAY 0.723404 (1650 5325);
FORCEPROP 1 LAST MATERIAL CHIP
J 0
(1900 5325);
DISPLAY 0.723404 (1900 5325);
FORCEPROP 1 LAST VALUE 33.2
J 2
(2075 5375);
DISPLAY 0.723404 (2075 5375);
FORCEPROP 2 LAST CDS_LIB pure_quanta
J 0
(1825 5375);
DISPLAY INVISIBLE (1825 5375);
FORCEPROP 1 LAST TOLERANCE 1%
J 0
(2300 5375);
DISPLAY 0.723404 (2300 5375);
PAINT SKYBLUE (2300 5375);
DISPLAY INVISIBLE (2300 5375);
FORCEPROP 1 LAST WATTAGE 1/16W
J 2
(2225 5325);
DISPLAY 0.723404 (2225 5325);
PAINT SKYBLUE (2225 5325);
DISPLAY INVISIBLE (2225 5325);
FORCEPROP 1 LAST PATH I22
J 0
(1775 5525);
DISPLAY 0.978723 (1775 5525);
PAINT WHITE (1775 5525);
DISPLAY INVISIBLE (1775 5525);
FORCEPROP 1 LAST PART_NUMBER CS03322FB03
J 0
(1425 5275);
DISPLAY 0.723404 (1425 5275);
PAINT WHITE (1425 5275);
DISPLAY INVISIBLE (1425 5275);
FORCEADD OFFPAGE..2
(2800 5375);
PAINT AQUA (2800 5375);
FORCEPROP 2 LAST $XR1 132 
J 0
(3109 5375);
DISPLAY 0.638298 (3109 5375);
PAINT MONO (3109 5375);
FORCEPROP 2 LAST $XR0 131 
J 0
(2989 5375);
DISPLAY 0.638298 (2989 5375);
PAINT MONO (2989 5375);
FORCEPROP 2 LAST CDS_LIB standard
J 0
(2800 5375);
DISPLAY INVISIBLE (2800 5375);
FORCEPROP 1 LAST OFFPAGE TRUE
J 0
(3125 5250);
DISPLAY 0.872340 (3125 5250);
PAINT AQUA (3125 5250);
DISPLAY INVISIBLE (3125 5250);
FORCEPROP 1 LAST COMMENT_BODY TRUE
J 0
(2755 5280);
DISPLAY 0.872340 (2755 5280);
PAINT GREEN (2755 5280);
DISPLAY INVISIBLE (2755 5280);
FORCEPROP 2 LAST PATH I23
J 0
(3125 5425);
DISPLAY 0.680851 (3125 5425);
DISPLAY INVISIBLE (3125 5425);
FORCEADD UNIVERSAL_GND..1
(150 6225);
FORCEPROP 3 LASTPIN (150 6275) SIG_NAME GND\g
J 0
(160 6285);
DISPLAY 0.659574 (160 6285);
PAINT MONO (160 6285);
DISPLAY INVISIBLE (160 6285);
FORCEPROP 2 LAST CDS_LIB pure_quanta_power
J 0
(150 6225);
DISPLAY INVISIBLE (150 6225);
FORCEPROP 1 LAST HDL_POWER GND
J 1
(175 6150);
DISPLAY 0.872340 (175 6150);
PAINT GREEN (175 6150);
DISPLAY INVISIBLE (175 6150);
FORCEPROP 1 LAST PATH I24
J 0
(225 6225);
DISPLAY 0.872340 (225 6225);
PAINT AQUA (225 6225);
DISPLAY INVISIBLE (225 6225);
FORCEADD 74LVC1G08W57..1
(500 6600);
FORCEPROP 1 LAST LOCATION U9001
J 0
(356 7031);
DISPLAY 0.723404 (356 7031);
PAINT GREEN (356 7031);
FORCEPROP 0 LAST $SEC 1
J 0
(375 7075);
DISPLAY 0.680851 (375 7075);
PAINT MONO (375 7075);
DISPLAY INVISIBLE (375 7075);
FORCEPROP 0 LAST CDS_SEC 1
J 0
(375 7075);
DISPLAY 0.680851 (375 7075);
DISPLAY INVISIBLE (375 7075);
FORCEPROP 0 LASTPIN (200 6700) $PN 1
J 2
(190 6710);
DISPLAY 0.680851 (190 6710);
PAINT MONO (190 6710);
FORCEPROP 0 LASTPIN (200 6600) $PN 2
J 2
(190 6610);
DISPLAY 0.680851 (190 6610);
PAINT MONO (190 6610);
FORCEPROP 0 LASTPIN (200 6500) $PN 3
J 2
(190 6510);
DISPLAY 0.680851 (190 6510);
PAINT MONO (190 6510);
FORCEPROP 0 LASTPIN (800 6700) $PN 5
J 0
(810 6710);
DISPLAY 0.680851 (810 6710);
PAINT MONO (810 6710);
FORCEPROP 0 LASTPIN (800 6550) $PN 4
J 0
(810 6560);
DISPLAY 0.680851 (810 6560);
PAINT MONO (810 6560);
FORCEPROP 2 LAST PART_TYPE SMLF
J 0
(350 6925);
DISPLAY 0.808511 (350 6925);
FORCEPROP 1 LAST MATERIAL IC
J 0
(356 6757);
DISPLAY 0.723404 (356 6757);
PAINT GREEN (356 6757);
FORCEPROP 2 LAST VALUE 74LVC1G08W5-7
J 0
(350 6875);
DISPLAY 0.808511 (350 6875);
FORCEPROP 1 LAST NEEDS_NO_SIZE TRUE
J 0
(500 6600);
DISPLAY 0.723404 (500 6600);
PAINT GREEN (500 6600);
DISPLAY INVISIBLE (500 6600);
FORCEPROP 2 LAST CDS_LIB pure_quanta
J 0
(500 6600);
DISPLAY INVISIBLE (500 6600);
FORCEPROP 1 LAST CDS_LMAN_SYM_OUTLINE -150,150,150,-150
J 0
(500 6600);
DISPLAY 0.468085 (500 6600);
PAINT GREEN (500 6600);
DISPLAY INVISIBLE (500 6600);
FORCEPROP 1 LAST PATH I25
J 0
(500 6600);
DISPLAY 0.723404 (500 6600);
PAINT GREEN (500 6600);
DISPLAY INVISIBLE (500 6600);
FORCEPROP 1 LAST PART_NUMBER AL1G0008020
J 0
(350 6825);
DISPLAY 0.723404 (350 6825);
PAINT GREEN (350 6825);
DISPLAY INVISIBLE (350 6825);
FORCEADD UNIVERSAL_GND..1
(1050 6675);
FORCEPROP 3 LASTPIN (1050 6725) SIG_NAME GND\g
J 0
(1060 6735);
DISPLAY 0.659574 (1060 6735);
PAINT MONO (1060 6735);
DISPLAY INVISIBLE (1060 6735);
FORCEPROP 2 LAST CDS_LIB pure_quanta_power
J 0
(1050 6675);
DISPLAY INVISIBLE (1050 6675);
FORCEPROP 1 LAST HDL_POWER GND
J 1
(1075 6600);
DISPLAY 0.872340 (1075 6600);
PAINT GREEN (1075 6600);
DISPLAY INVISIBLE (1075 6600);
FORCEPROP 1 LAST PATH I26
J 0
(1125 6675);
DISPLAY 0.872340 (1125 6675);
PAINT AQUA (1125 6675);
DISPLAY INVISIBLE (1125 6675);
FORCEADD Q_CAP..1
(1050 6875);
FORCEPROP 1 LAST LOCATION C9007
J 0
(1100 6975);
DISPLAY 0.787234 (1100 6975);
FORCEPROP 0 LAST $SEC 1
J 0
(1100 7025);
DISPLAY 0.680851 (1100 7025);
PAINT MONO (1100 7025);
DISPLAY INVISIBLE (1100 7025);
FORCEPROP 0 LAST CDS_SEC 1
J 0
(1100 7025);
DISPLAY 0.680851 (1100 7025);
DISPLAY INVISIBLE (1100 7025);
FORCEPROP 1 LASTPIN (1050 6975) $PN 1
J 0
(1060 6955);
DISPLAY 0.787234 (1060 6955);
PAINT MONO (1060 6955);
FORCEPROP 1 LASTPIN (1050 6775) $PN 2
J 0
(1060 6755);
DISPLAY 0.787234 (1060 6755);
PAINT MONO (1060 6755);
FORCEPROP 1 LAST MATERIAL X7R
J 0
(1100 6775);
DISPLAY 0.787234 (1100 6775);
PAINT RED (1100 6775);
FORCEPROP 1 LAST PACK_TYPE 0402
J 0
(1100 6675);
DISPLAY 0.787234 (1100 6675);
FORCEPROP 1 LAST TOLERANCE 10%
J 0
(1100 6825);
DISPLAY 0.787234 (1100 6825);
FORCEPROP 1 LAST VALUE 0.1UF
J 0
(1100 6925);
DISPLAY 0.787234 (1100 6925);
FORCEPROP 1 LAST VOLTAGE 25V
J 0
(1100 6875);
DISPLAY 0.787234 (1100 6875);
FORCEPROP 2 LAST CDS_LIB pure_quanta
J 0
(1050 6875);
DISPLAY INVISIBLE (1050 6875);
FORCEPROP 1 LAST PATH I27
J 0
(1100 7025);
DISPLAY 0.978723 (1100 7025);
PAINT WHITE (1100 7025);
DISPLAY INVISIBLE (1100 7025);
FORCEPROP 1 LAST PART_NUMBER CH4104K1B00
J 0
(1100 6725);
DISPLAY 0.787234 (1100 6725);
DISPLAY INVISIBLE (1100 6725);
FORCEADD UNIVERSAL_POWER..1
R 2
(1050 7150);
FORCEPROP 3 LASTPIN (1050 7100) SIG_NAME P3V3_AUX\g
J 0
(1060 7110);
DISPLAY 0.659574 (1060 7110);
PAINT MONO (1060 7110);
DISPLAY INVISIBLE (1060 7110);
FORCEPROP 1 LAST HDL_POWER P3V3_AUX
J 1
(1050 7200);
DISPLAY 0.723404 (1050 7200);
PAINT GREEN (1050 7200);
FORCEPROP 2 LAST CDS_LIB pure_quanta_power
J 0
(1050 7150);
DISPLAY INVISIBLE (1050 7150);
FORCEPROP 1 LAST PATH I28
J 2
(1000 7175);
DISPLAY 0.872340 (1000 7175);
PAINT AQUA (1000 7175);
DISPLAY INVISIBLE (1000 7175);
FORCEADD Q_RES..1
(2050 6550);
FORCEPROP 1 LAST LOCATION R9033
J 0
(1850 6550);
DISPLAY 0.723404 (1850 6550);
FORCEPROP 0 LAST $SEC 1
J 0
(2300 6600);
DISPLAY 0.680851 (2300 6600);
PAINT MONO (2300 6600);
DISPLAY INVISIBLE (2300 6600);
FORCEPROP 0 LAST CDS_SEC 1
J 0
(2300 6600);
DISPLAY 0.680851 (2300 6600);
DISPLAY INVISIBLE (2300 6600);
FORCEPROP 1 LASTPIN (1950 6550) $PN 1
J 0
(1962 6562);
DISPLAY 0.787234 (1962 6562);
PAINT MONO (1962 6562);
FORCEPROP 1 LASTPIN (2150 6550) $PN 2
J 0
(2112 6562);
DISPLAY 0.787234 (2112 6562);
PAINT MONO (2112 6562);
FORCEPROP 1 LAST MATERIAL CHIP
J 0
(2125 6500);
DISPLAY 0.723404 (2125 6500);
FORCEPROP 1 LAST VALUE 33.2
J 2
(2300 6550);
DISPLAY 0.723404 (2300 6550);
FORCEPROP 1 LAST PACK_TYPE 0402LF
J 0
(1875 6500);
DISPLAY 0.723404 (1875 6500);
FORCEPROP 1 LAST WATTAGE 1/16W
J 2
(2450 6500);
DISPLAY 0.723404 (2450 6500);
PAINT SKYBLUE (2450 6500);
DISPLAY INVISIBLE (2450 6500);
FORCEPROP 1 LAST TOLERANCE 1%
J 0
(2525 6550);
DISPLAY 0.723404 (2525 6550);
PAINT SKYBLUE (2525 6550);
DISPLAY INVISIBLE (2525 6550);
FORCEPROP 2 LAST CDS_LIB pure_quanta
J 0
(2050 6550);
DISPLAY INVISIBLE (2050 6550);
FORCEPROP 1 LAST PATH I29
J 0
(2000 6700);
DISPLAY 0.978723 (2000 6700);
PAINT WHITE (2000 6700);
DISPLAY INVISIBLE (2000 6700);
FORCEPROP 1 LAST PART_NUMBER CS03322FB03
J 0
(1650 6450);
DISPLAY 0.723404 (1650 6450);
PAINT WHITE (1650 6450);
DISPLAY INVISIBLE (1650 6450);
FORCEADD Q_RES..1
(-1075 5425);
FORCEPROP 1 LAST LOCATION R9034
J 0
(-1275 5425);
DISPLAY 0.723404 (-1275 5425);
FORCEPROP 0 LAST $SEC 1
J 0
(-825 5475);
DISPLAY 0.680851 (-825 5475);
PAINT MONO (-825 5475);
DISPLAY INVISIBLE (-825 5475);
FORCEPROP 0 LAST CDS_SEC 1
J 0
(-825 5475);
DISPLAY 0.680851 (-825 5475);
DISPLAY INVISIBLE (-825 5475);
FORCEPROP 1 LASTPIN (-1175 5425) $PN 1
J 0
(-1163 5437);
DISPLAY 0.787234 (-1163 5437);
PAINT MONO (-1163 5437);
FORCEPROP 1 LASTPIN (-975 5425) $PN 2
J 0
(-1013 5437);
DISPLAY 0.787234 (-1013 5437);
PAINT MONO (-1013 5437);
FORCEPROP 1 LAST VALUE 33.2
J 2
(-825 5425);
DISPLAY 0.723404 (-825 5425);
FORCEPROP 1 LAST MATERIAL CHIP
J 0
(-1050 5375);
DISPLAY 0.723404 (-1050 5375);
FORCEPROP 1 LAST PACK_TYPE 0402LF
J 0
(-1250 5375);
DISPLAY 0.723404 (-1250 5375);
FORCEPROP 1 LAST WATTAGE 1/16W
J 2
(-675 5375);
DISPLAY 0.723404 (-675 5375);
PAINT SKYBLUE (-675 5375);
DISPLAY INVISIBLE (-675 5375);
FORCEPROP 1 LAST TOLERANCE 1%
J 0
(-600 5425);
DISPLAY 0.723404 (-600 5425);
PAINT SKYBLUE (-600 5425);
DISPLAY INVISIBLE (-600 5425);
FORCEPROP 2 LAST CDS_LIB pure_quanta
J 0
(-1075 5425);
DISPLAY INVISIBLE (-1075 5425);
FORCEPROP 1 LAST PATH I3
J 0
(-1125 5575);
DISPLAY 0.978723 (-1125 5575);
PAINT WHITE (-1125 5575);
DISPLAY INVISIBLE (-1125 5575);
FORCEPROP 1 LAST PART_NUMBER CS03322FB03
J 0
(-1475 5325);
DISPLAY 0.723404 (-1475 5325);
PAINT WHITE (-1475 5325);
DISPLAY INVISIBLE (-1475 5325);
FORCEADD OFFPAGE..2
(3150 6550);
PAINT AQUA (3150 6550);
FORCEPROP 2 LAST $XR0 133 
J 0
(3339 6550);
DISPLAY 0.638298 (3339 6550);
PAINT MONO (3339 6550);
FORCEPROP 2 LAST CDS_LIB standard
J 0
(3150 6550);
DISPLAY INVISIBLE (3150 6550);
FORCEPROP 1 LAST OFFPAGE TRUE
J 0
(3475 6425);
DISPLAY 0.872340 (3475 6425);
PAINT AQUA (3475 6425);
DISPLAY INVISIBLE (3475 6425);
FORCEPROP 1 LAST COMMENT_BODY TRUE
J 0
(3105 6455);
DISPLAY 0.872340 (3105 6455);
PAINT GREEN (3105 6455);
DISPLAY INVISIBLE (3105 6455);
FORCEPROP 2 LAST PATH I30
J 0
(3350 6600);
DISPLAY 0.680851 (3350 6600);
DISPLAY INVISIBLE (3350 6600);
FORCEADD MOSFET_N..1
(-3925 8950);
FORCEPROP 1 LAST LOCATION U24
J 0
(-3753 8641);
DISPLAY 0.723404 (-3753 8641);
PAINT GREEN (-3753 8641);
FORCEPROP 0 LAST $SEC 1
J 0
(-3750 8875);
DISPLAY 0.680851 (-3750 8875);
PAINT MONO (-3750 8875);
DISPLAY INVISIBLE (-3750 8875);
FORCEPROP 0 LAST CDS_SEC 1
J 0
(-3750 8875);
DISPLAY 0.680851 (-3750 8875);
DISPLAY INVISIBLE (-3750 8875);
FORCEPROP 1 LASTPIN (-3875 9050) $PN D
R 1
J 0
(-3875 9043);
DISPLAY 0.659574 (-3875 9043);
PAINT MONO (-3875 9043);
FORCEPROP 1 LASTPIN (-4025 8850) $PN G
J 2
(-4015 8853);
DISPLAY 0.659574 (-4015 8853);
PAINT MONO (-4015 8853);
FORCEPROP 1 LASTPIN (-3875 8750) $PN S
R 1
J 2
(-3875 8763);
DISPLAY 0.659574 (-3875 8763);
PAINT MONO (-3875 8763);
FORCEPROP 1 LAST MATERIAL IC
J 0
(-3753 8481);
DISPLAY 0.723404 (-3753 8481);
PAINT GREEN (-3753 8481);
FORCEPROP 1 LAST VALUE BSS138K
J 0
(-3753 8721);
DISPLAY 0.723404 (-3753 8721);
PAINT GREEN (-3753 8721);
FORCEPROP 2 LAST MANUF_PN BSS138K
J 0
(-3750 8825);
DISPLAY 0.680851 (-3750 8825);
FORCEPROP 2 LAST PATH I31
J 0
(-3750 8775);
DISPLAY 0.680851 (-3750 8775);
FORCEPROP 1 LAST PACK_TYPE SMLF
J 0
(-3900 8700);
DISPLAY 0.723404 (-3900 8700);
PAINT GREEN (-3900 8700);
DISPLAY INVISIBLE (-3900 8700);
FORCEPROP 2 LAST CDS_LIB pure_quanta
J 0
(-3925 8950);
DISPLAY INVISIBLE (-3925 8950);
FORCEPROP 1 LAST CDS_LMAN_SYM_OUTLINE -50,50,100,-150
J 0
(-3925 8950);
DISPLAY 0.468085 (-3925 8950);
PAINT GREEN (-3925 8950);
DISPLAY INVISIBLE (-3925 8950);
FORCEPROP 1 LAST PART_NUMBER BAM138K0000
J 0
(-3753 8561);
DISPLAY 0.723404 (-3753 8561);
PAINT GREEN (-3753 8561);
DISPLAY INVISIBLE (-3753 8561);
FORCEADD UNIVERSAL_GND..1
(-3875 8400);
FORCEPROP 3 LASTPIN (-3875 8450) SIG_NAME GND\g
J 0
(-3865 8460);
DISPLAY 0.659574 (-3865 8460);
PAINT MONO (-3865 8460);
DISPLAY INVISIBLE (-3865 8460);
FORCEPROP 2 LAST CDS_LIB pure_quanta_power
J 0
(-3875 8400);
DISPLAY INVISIBLE (-3875 8400);
FORCEPROP 1 LAST HDL_POWER GND
J 1
(-3850 8325);
DISPLAY 0.872340 (-3850 8325);
PAINT GREEN (-3850 8325);
DISPLAY INVISIBLE (-3850 8325);
FORCEPROP 1 LAST PATH I32
J 0
(-3800 8400);
DISPLAY 0.872340 (-3800 8400);
PAINT AQUA (-3800 8400);
DISPLAY INVISIBLE (-3800 8400);
FORCEADD OFFPAGE..1
(-5000 8850);
PAINT AQUA (-5000 8850);
FORCEPROP 2 LAST $XR0 134 
J 0
(-5252 8850);
DISPLAY 0.638298 (-5252 8850);
PAINT MONO (-5252 8850);
FORCEPROP 2 LAST CDS_LIB standard
J 0
(-5000 8850);
DISPLAY INVISIBLE (-5000 8850);
FORCEPROP 1 LAST OFFPAGE TRUE
J 0
(-4675 8725);
DISPLAY 0.872340 (-4675 8725);
PAINT AQUA (-4675 8725);
DISPLAY INVISIBLE (-4675 8725);
FORCEPROP 1 LAST COMMENT_BODY TRUE
J 0
(-4875 8750);
DISPLAY 0.872340 (-4875 8750);
PAINT GREEN (-4875 8750);
DISPLAY INVISIBLE (-4875 8750);
FORCEPROP 2 LAST PATH I33
J 0
(-4950 8925);
DISPLAY 0.680851 (-4950 8925);
DISPLAY INVISIBLE (-4950 8925);
FORCEADD Q_RES..2
R 2
(-3875 9500);
FORCEPROP 1 LAST LOCATION R1128
J 2
(-3920 9625);
DISPLAY 0.978723 (-3920 9625);
FORCEPROP 0 LAST $SEC 1
J 0
(-3900 9675);
DISPLAY 0.680851 (-3900 9675);
PAINT MONO (-3900 9675);
DISPLAY INVISIBLE (-3900 9675);
FORCEPROP 0 LAST CDS_SEC 1
J 0
(-3900 9675);
DISPLAY 0.680851 (-3900 9675);
DISPLAY INVISIBLE (-3900 9675);
FORCEPROP 1 LASTPIN (-3875 9600) $PN 1
J 2
(-3880 9562);
DISPLAY 0.787234 (-3880 9562);
PAINT MONO (-3880 9562);
FORCEPROP 1 LASTPIN (-3875 9400) $PN 2
J 2
(-3880 9410);
DISPLAY 0.787234 (-3880 9410);
PAINT MONO (-3880 9410);
FORCEPROP 1 LAST TOLERANCE 1%
J 2
(-3920 9525);
DISPLAY 0.978723 (-3920 9525);
FORCEPROP 1 LAST VALUE 1K
J 2
(-3920 9575);
DISPLAY 0.978723 (-3920 9575);
FORCEPROP 1 LAST WATTAGE 1/16W
J 2
(-3915 9475);
DISPLAY 0.978723 (-3915 9475);
FORCEPROP 1 LAST MATERIAL CHIP
J 2
(-3915 9425);
DISPLAY 0.978723 (-3915 9425);
FORCEPROP 1 LAST PACK_TYPE 0402LF
J 2
(-3915 9325);
DISPLAY 0.978723 (-3915 9325);
FORCEPROP 2 LAST CDS_LIB pure_quanta
J 2
(-3875 9500);
DISPLAY INVISIBLE (-3875 9500);
FORCEPROP 1 LAST PATH I34
J 2
(-3925 9675);
DISPLAY 0.978723 (-3925 9675);
PAINT WHITE (-3925 9675);
DISPLAY INVISIBLE (-3925 9675);
FORCEPROP 1 LAST PART_NUMBER CS21002FB06
J 2
(-3915 9375);
DISPLAY 0.978723 (-3915 9375);
DISPLAY INVISIBLE (-3915 9375);
FORCEADD UNIVERSAL_POWER..1
R 2
(-3875 9900);
FORCEPROP 3 LASTPIN (-3875 9850) SIG_NAME P3V3_AUX\g
J 0
(-3865 9860);
DISPLAY 0.659574 (-3865 9860);
PAINT MONO (-3865 9860);
DISPLAY INVISIBLE (-3865 9860);
FORCEPROP 1 LAST HDL_POWER P3V3_AUX
J 1
(-3875 9950);
DISPLAY 0.723404 (-3875 9950);
PAINT GREEN (-3875 9950);
FORCEPROP 2 LAST CDS_LIB pure_quanta_power
J 0
(-3875 9900);
DISPLAY INVISIBLE (-3875 9900);
FORCEPROP 1 LAST PATH I35
J 2
(-3925 9925);
DISPLAY 0.872340 (-3925 9925);
PAINT AQUA (-3925 9925);
DISPLAY INVISIBLE (-3925 9925);
FORCEADD 74LVC1G08W57..1
(-750 9200);
FORCEPROP 1 LAST LOCATION U23
J 0
(-894 9631);
DISPLAY 0.723404 (-894 9631);
PAINT GREEN (-894 9631);
FORCEPROP 2 LAST SEC 1
J 0
(-875 9675);
DISPLAY 0.680851 (-875 9675);
PAINT MONO (-875 9675);
DISPLAY INVISIBLE (-875 9675);
FORCEPROP 2 LASTPIN (-1050 9300) $PN 1
J 2
(-1060 9310);
DISPLAY 0.680851 (-1060 9310);
PAINT MONO (-1060 9310);
FORCEPROP 2 LASTPIN (-1050 9200) $PN 2
J 2
(-1060 9210);
DISPLAY 0.680851 (-1060 9210);
PAINT MONO (-1060 9210);
FORCEPROP 2 LASTPIN (-1050 9100) $PN 3
J 2
(-1060 9110);
DISPLAY 0.680851 (-1060 9110);
PAINT MONO (-1060 9110);
FORCEPROP 2 LASTPIN (-450 9300) $PN 5
J 0
(-440 9310);
DISPLAY 0.680851 (-440 9310);
PAINT MONO (-440 9310);
FORCEPROP 2 LASTPIN (-450 9150) $PN 4
J 0
(-440 9160);
DISPLAY 0.680851 (-440 9160);
PAINT MONO (-440 9160);
FORCEPROP 1 LAST MATERIAL IC
J 0
(-894 9357);
DISPLAY 0.723404 (-894 9357);
PAINT GREEN (-894 9357);
FORCEPROP 2 LAST VALUE 74LVC1G08W5-7
J 0
(-900 9475);
DISPLAY 0.808511 (-900 9475);
FORCEPROP 2 LAST PART_TYPE SMLF
J 0
(-900 9525);
DISPLAY 0.808511 (-900 9525);
FORCEPROP 1 LAST NEEDS_NO_SIZE TRUE
J 0
(-750 9200);
DISPLAY 0.723404 (-750 9200);
PAINT GREEN (-750 9200);
DISPLAY INVISIBLE (-750 9200);
FORCEPROP 1 LAST CDS_LMAN_SYM_OUTLINE -150,150,150,-150
J 0
(-750 9200);
DISPLAY 0.468085 (-750 9200);
PAINT GREEN (-750 9200);
DISPLAY INVISIBLE (-750 9200);
FORCEPROP 2 LAST CDS_LIB pure_quanta
J 0
(-750 9200);
DISPLAY INVISIBLE (-750 9200);
FORCEPROP 2 LAST SEC_TYPE 
J 0
(-875 9675);
DISPLAY 0.680851 (-875 9675);
DISPLAY INVISIBLE (-875 9675);
FORCEPROP 1 LAST PATH I36
J 0
(-750 9200);
DISPLAY 0.723404 (-750 9200);
PAINT GREEN (-750 9200);
DISPLAY INVISIBLE (-750 9200);
FORCEPROP 1 LAST PART_NUMBER AL1G0008020
J 0
(-900 9425);
DISPLAY 0.723404 (-900 9425);
PAINT GREEN (-900 9425);
DISPLAY INVISIBLE (-900 9425);
FORCEADD UNIVERSAL_GND..1
(-1325 8825);
FORCEPROP 3 LASTPIN (-1325 8875) SIG_NAME GND\g
J 0
(-1315 8885);
DISPLAY 0.659574 (-1315 8885);
PAINT MONO (-1315 8885);
DISPLAY INVISIBLE (-1315 8885);
FORCEPROP 2 LAST CDS_LIB pure_quanta_power
J 0
(-1325 8825);
DISPLAY INVISIBLE (-1325 8825);
FORCEPROP 1 LAST HDL_POWER GND
J 1
(-1300 8750);
DISPLAY 0.872340 (-1300 8750);
PAINT GREEN (-1300 8750);
DISPLAY INVISIBLE (-1300 8750);
FORCEPROP 1 LAST PATH I37
J 0
(-1250 8825);
DISPLAY 0.872340 (-1250 8825);
PAINT AQUA (-1250 8825);
DISPLAY INVISIBLE (-1250 8825);
FORCEADD UNIVERSAL_POWER..1
R 2
(-150 9825);
FORCEPROP 3 LASTPIN (-150 9775) SIG_NAME P3V3_AUX\g
J 0
(-140 9785);
DISPLAY 0.659574 (-140 9785);
PAINT MONO (-140 9785);
DISPLAY INVISIBLE (-140 9785);
FORCEPROP 1 LAST HDL_POWER P3V3_AUX
J 1
(-150 9875);
DISPLAY 0.723404 (-150 9875);
PAINT GREEN (-150 9875);
FORCEPROP 2 LAST CDS_LIB pure_quanta_power
J 0
(-150 9825);
DISPLAY INVISIBLE (-150 9825);
FORCEPROP 1 LAST PATH I39
J 2
(-200 9850);
DISPLAY 0.872340 (-200 9850);
PAINT AQUA (-200 9850);
DISPLAY INVISIBLE (-200 9850);
FORCEADD UNIVERSAL_POWER..1
R 2
(-1625 5975);
FORCEPROP 3 LASTPIN (-1625 5925) SIG_NAME P3V3_AUX\g
J 0
(-1615 5935);
DISPLAY 0.659574 (-1615 5935);
PAINT MONO (-1615 5935);
DISPLAY INVISIBLE (-1615 5935);
FORCEPROP 1 LAST HDL_POWER P3V3_AUX
J 1
(-1625 6025);
DISPLAY 0.723404 (-1625 6025);
PAINT GREEN (-1625 6025);
FORCEPROP 2 LAST CDS_LIB pure_quanta_power
J 0
(-1625 5975);
DISPLAY INVISIBLE (-1625 5975);
FORCEPROP 1 LAST PATH I4
J 2
(-1675 6000);
DISPLAY 0.872340 (-1675 6000);
PAINT AQUA (-1675 6000);
DISPLAY INVISIBLE (-1675 6000);
FORCEADD Q_CAP..1
(-150 9550);
FORCEPROP 1 LAST LOCATION C1059
J 0
(-100 9700);
DISPLAY 0.787234 (-100 9700);
FORCEPROP 0 LAST $SEC 1
J 0
(-100 9750);
DISPLAY 0.680851 (-100 9750);
PAINT MONO (-100 9750);
DISPLAY INVISIBLE (-100 9750);
FORCEPROP 0 LAST CDS_SEC 1
J 0
(-100 9750);
DISPLAY 0.680851 (-100 9750);
DISPLAY INVISIBLE (-100 9750);
FORCEPROP 1 LASTPIN (-150 9650) $PN 1
J 0
(-140 9630);
DISPLAY 0.787234 (-140 9630);
PAINT MONO (-140 9630);
FORCEPROP 1 LASTPIN (-150 9450) $PN 2
J 0
(-140 9430);
DISPLAY 0.787234 (-140 9430);
PAINT MONO (-140 9430);
FORCEPROP 1 LAST VOLTAGE 25V
J 0
(-100 9600);
DISPLAY 0.787234 (-100 9600);
FORCEPROP 1 LAST PACK_TYPE 0402
J 0
(-100 9400);
DISPLAY 0.787234 (-100 9400);
FORCEPROP 1 LAST VALUE 0.1UF
J 0
(-100 9650);
DISPLAY 0.787234 (-100 9650);
FORCEPROP 1 LAST MATERIAL X7R
J 0
(-100 9500);
DISPLAY 0.787234 (-100 9500);
PAINT RED (-100 9500);
FORCEPROP 1 LAST TOLERANCE 10%
J 0
(-100 9550);
DISPLAY 0.787234 (-100 9550);
FORCEPROP 2 LAST CDS_LIB pure_quanta
J 0
(-150 9550);
DISPLAY INVISIBLE (-150 9550);
FORCEPROP 1 LAST PATH I40
J 0
(-100 9700);
DISPLAY 0.978723 (-100 9700);
PAINT WHITE (-100 9700);
DISPLAY INVISIBLE (-100 9700);
FORCEPROP 1 LAST PART_NUMBER CH4104K1B00
J 0
(-100 9450);
DISPLAY 0.787234 (-100 9450);
DISPLAY INVISIBLE (-100 9450);
FORCEADD UNIVERSAL_GND..1
(-150 9250);
FORCEPROP 3 LASTPIN (-150 9300) SIG_NAME GND\g
J 0
(-140 9310);
DISPLAY 0.659574 (-140 9310);
PAINT MONO (-140 9310);
DISPLAY INVISIBLE (-140 9310);
FORCEPROP 2 LAST CDS_LIB pure_quanta_power
J 0
(-150 9250);
DISPLAY INVISIBLE (-150 9250);
FORCEPROP 1 LAST HDL_POWER GND
J 1
(-125 9175);
DISPLAY 0.872340 (-125 9175);
PAINT GREEN (-125 9175);
DISPLAY INVISIBLE (-125 9175);
FORCEPROP 1 LAST PATH I41
J 0
(-75 9250);
DISPLAY 0.872340 (-75 9250);
PAINT AQUA (-75 9250);
DISPLAY INVISIBLE (-75 9250);
FORCEADD UNIVERSAL_POWER..1
R 2
(-1225 10125);
FORCEPROP 3 LASTPIN (-1225 10075) SIG_NAME P3V3_AUX\g
J 0
(-1215 10085);
DISPLAY 0.659574 (-1215 10085);
PAINT MONO (-1215 10085);
DISPLAY INVISIBLE (-1215 10085);
FORCEPROP 1 LAST HDL_POWER P3V3_AUX
J 1
(-1225 10175);
DISPLAY 0.723404 (-1225 10175);
PAINT GREEN (-1225 10175);
FORCEPROP 2 LAST CDS_LIB pure_quanta_power
J 0
(-1225 10125);
DISPLAY INVISIBLE (-1225 10125);
FORCEPROP 1 LAST PATH I43
J 2
(-1275 10150);
DISPLAY 0.872340 (-1275 10150);
PAINT AQUA (-1275 10150);
DISPLAY INVISIBLE (-1275 10150);
FORCEADD Q_RES..2
R 2
(-1225 9725);
FORCEPROP 1 LAST LOCATION R1131
J 2
(-1270 9850);
DISPLAY 0.978723 (-1270 9850);
FORCEPROP 0 LAST $SEC 1
J 0
(-1250 9900);
DISPLAY 0.680851 (-1250 9900);
PAINT MONO (-1250 9900);
DISPLAY INVISIBLE (-1250 9900);
FORCEPROP 0 LAST CDS_SEC 1
J 0
(-1250 9900);
DISPLAY 0.680851 (-1250 9900);
DISPLAY INVISIBLE (-1250 9900);
FORCEPROP 1 LASTPIN (-1225 9825) $PN 1
J 2
(-1230 9787);
DISPLAY 0.787234 (-1230 9787);
PAINT MONO (-1230 9787);
FORCEPROP 1 LASTPIN (-1225 9625) $PN 2
J 2
(-1230 9635);
DISPLAY 0.787234 (-1230 9635);
PAINT MONO (-1230 9635);
FORCEPROP 1 LAST VALUE 1K
J 2
(-1270 9800);
DISPLAY 0.978723 (-1270 9800);
FORCEPROP 1 LAST PACK_TYPE 0402LF
J 2
(-1265 9550);
DISPLAY 0.978723 (-1265 9550);
FORCEPROP 1 LAST WATTAGE 1/16W
J 2
(-1265 9700);
DISPLAY 0.978723 (-1265 9700);
FORCEPROP 1 LAST MATERIAL CHIP
J 2
(-1265 9650);
DISPLAY 0.978723 (-1265 9650);
FORCEPROP 1 LAST TOLERANCE 1%
J 2
(-1270 9750);
DISPLAY 0.978723 (-1270 9750);
FORCEPROP 2 LAST CDS_LIB pure_quanta
J 0
(-1225 9725);
DISPLAY INVISIBLE (-1225 9725);
FORCEPROP 1 LAST PATH I44
J 2
(-1275 9900);
DISPLAY 0.978723 (-1275 9900);
PAINT WHITE (-1275 9900);
DISPLAY INVISIBLE (-1275 9900);
FORCEPROP 1 LAST PART_NUMBER CS21002FB06
J 2
(-1265 9600);
DISPLAY 0.978723 (-1265 9600);
DISPLAY INVISIBLE (-1265 9600);
FORCEADD Q_RES..1
(650 9150);
FORCEPROP 1 LAST LOCATION R1134
J 0
(600 9200);
DISPLAY 0.978723 (600 9200);
FORCEPROP 0 LAST $SEC 1
J 0
(600 9250);
DISPLAY 0.680851 (600 9250);
PAINT MONO (600 9250);
DISPLAY INVISIBLE (600 9250);
FORCEPROP 0 LAST CDS_SEC 1
J 0
(600 9250);
DISPLAY 0.680851 (600 9250);
DISPLAY INVISIBLE (600 9250);
FORCEPROP 1 LASTPIN (550 9150) $PN 1
J 0
(562 9162);
DISPLAY 0.787234 (562 9162);
PAINT MONO (562 9162);
FORCEPROP 1 LASTPIN (750 9150) $PN 2
J 0
(712 9162);
DISPLAY 0.787234 (712 9162);
PAINT MONO (712 9162);
FORCEPROP 1 LAST WATTAGE 1/16W
J 2
(850 9075);
DISPLAY 0.510638 (850 9075);
FORCEPROP 1 LAST MATERIAL CHIP
J 0
(575 9075);
DISPLAY 0.510638 (575 9075);
PAINT RED (575 9075);
FORCEPROP 1 LAST TOLERANCE 5%
J 0
(825 9150);
DISPLAY 0.510638 (825 9150);
FORCEPROP 1 LAST VALUE 0
J 2
(800 9150);
DISPLAY 0.510638 (800 9150);
FORCEPROP 1 LAST PACK_TYPE 0402LF
J 0
(900 9150);
DISPLAY 0.510638 (900 9150);
FORCEPROP 2 LAST CDS_LIB pure_quanta
J 0
(650 9150);
DISPLAY INVISIBLE (650 9150);
FORCEPROP 1 LAST PATH I47
J 0
(600 9300);
DISPLAY 0.978723 (600 9300);
PAINT WHITE (600 9300);
DISPLAY INVISIBLE (600 9300);
FORCEPROP 1 LAST PART_NUMBER CS00002JB13
J 0
(575 9100);
DISPLAY 0.510638 (575 9100);
DISPLAY INVISIBLE (575 9100);
FORCEADD OFFPAGE..2
(1850 9150);
PAINT AQUA (1850 9150);
FORCEPROP 2 LAST $XR2 248 
J 0
(2279 9150);
DISPLAY 0.638298 (2279 9150);
PAINT MONO (2279 9150);
FORCEPROP 2 LAST $XR1 135 
J 0
(2159 9150);
DISPLAY 0.638298 (2159 9150);
PAINT MONO (2159 9150);
FORCEPROP 2 LAST $XR0 134 
J 0
(2039 9150);
DISPLAY 0.638298 (2039 9150);
PAINT MONO (2039 9150);
FORCEPROP 2 LAST CDS_LIB standard
J 0
(1850 9150);
DISPLAY INVISIBLE (1850 9150);
FORCEPROP 1 LAST OFFPAGE TRUE
J 0
(2175 9025);
DISPLAY 0.872340 (2175 9025);
PAINT AQUA (2175 9025);
DISPLAY INVISIBLE (2175 9025);
FORCEPROP 1 LAST COMMENT_BODY TRUE
J 0
(1805 9055);
DISPLAY 0.872340 (1805 9055);
PAINT GREEN (1805 9055);
DISPLAY INVISIBLE (1805 9055);
FORCEPROP 2 LAST PATH I48
J 0
(2025 9225);
DISPLAY 0.680851 (2025 9225);
DISPLAY INVISIBLE (2025 9225);
FORCEADD Q_RES..1
(-2125 9300);
FORCEPROP 1 LAST LOCATION R1130
J 0
(-2175 9325);
DISPLAY 0.638298 (-2175 9325);
FORCEPROP 0 LAST $SEC 1
J 0
(-2175 9375);
DISPLAY 0.680851 (-2175 9375);
PAINT MONO (-2175 9375);
DISPLAY INVISIBLE (-2175 9375);
FORCEPROP 0 LAST CDS_SEC 1
J 0
(-2175 9375);
DISPLAY 0.680851 (-2175 9375);
DISPLAY INVISIBLE (-2175 9375);
FORCEPROP 1 LASTPIN (-2225 9300) $PN 1
J 0
(-2213 9312);
DISPLAY 0.787234 (-2213 9312);
PAINT MONO (-2213 9312);
FORCEPROP 1 LASTPIN (-2025 9300) $PN 2
J 0
(-2063 9312);
DISPLAY 0.787234 (-2063 9312);
PAINT MONO (-2063 9312);
FORCEPROP 1 LAST MATERIAL EMPTY
J 0
(-2325 9300);
DISPLAY 0.510638 (-2325 9300);
PAINT RED (-2325 9300);
FORCEPROP 1 LAST TOLERANCE 5%
J 0
(-1950 9300);
DISPLAY 0.510638 (-1950 9300);
FORCEPROP 1 LAST VALUE 0
J 2
(-1975 9300);
DISPLAY 0.510638 (-1975 9300);
FORCEPROP 1 LAST WATTAGE 1/16W
J 2
(-2025 9225);
DISPLAY 0.319149 (-2025 9225);
DISPLAY INVISIBLE (-2025 9225);
FORCEPROP 1 LAST PACK_TYPE 0402LF
J 0
(-1875 9300);
DISPLAY 0.510638 (-1875 9300);
DISPLAY INVISIBLE (-1875 9300);
FORCEPROP 2 LAST CDS_LIB pure_quanta
J 0
(-2125 9300);
DISPLAY INVISIBLE (-2125 9300);
FORCEPROP 1 LAST PATH I49
J 0
(-2175 9450);
DISPLAY 0.978723 (-2175 9450);
PAINT WHITE (-2175 9450);
DISPLAY INVISIBLE (-2175 9450);
FORCEPROP 1 LAST PART_NUMBER CS00002JB13
J 0
(-2200 9250);
DISPLAY 0.319149 (-2200 9250);
DISPLAY INVISIBLE (-2200 9250);
FORCEADD OFFPAGE..1
(-3050 9300);
PAINT AQUA (-3050 9300);
FORCEPROP 2 LAST $XR3 135 
J 0
(-3631 9300);
DISPLAY 0.638298 (-3631 9300);
PAINT MONO (-3631 9300);
FORCEPROP 2 LAST $XR2 134 
J 0
(-3511 9300);
DISPLAY 0.638298 (-3511 9300);
PAINT MONO (-3511 9300);
FORCEPROP 2 LAST $XR1 83 
J 0
(-3391 9300);
DISPLAY 0.638298 (-3391 9300);
PAINT MONO (-3391 9300);
FORCEPROP 2 LAST $XR0 80 
J 0
(-3301 9300);
DISPLAY 0.638298 (-3301 9300);
PAINT MONO (-3301 9300);
FORCEPROP 2 LAST CDS_LIB standard
J 0
(-3050 9300);
DISPLAY INVISIBLE (-3050 9300);
FORCEPROP 1 LAST OFFPAGE TRUE
J 0
(-2725 9175);
DISPLAY 0.872340 (-2725 9175);
PAINT AQUA (-2725 9175);
DISPLAY INVISIBLE (-2725 9175);
FORCEPROP 1 LAST COMMENT_BODY TRUE
J 0
(-2925 9200);
DISPLAY 0.872340 (-2925 9200);
PAINT GREEN (-2925 9200);
DISPLAY INVISIBLE (-2925 9200);
FORCEPROP 2 LAST PATH I50
J 0
(-3000 9375);
DISPLAY 0.680851 (-3000 9375);
DISPLAY INVISIBLE (-3000 9375);
FORCEADD SN74LVC1G07DBVR..1
(-2375 7450);
FORCEPROP 1 LAST LOCATION U28
J 0
(-2500 7705);
DISPLAY 0.723404 (-2500 7705);
PAINT GREEN (-2500 7705);
FORCEPROP 0 LAST $SEC 1
J 0
(-2500 7850);
DISPLAY 0.680851 (-2500 7850);
PAINT MONO (-2500 7850);
DISPLAY INVISIBLE (-2500 7850);
FORCEPROP 0 LAST CDS_SEC 1
J 0
(-2500 7850);
DISPLAY 0.680851 (-2500 7850);
DISPLAY INVISIBLE (-2500 7850);
FORCEPROP 0 LASTPIN (-2550 7450) $PN 2
J 2
(-2560 7460);
DISPLAY 0.680851 (-2560 7460);
PAINT MONO (-2560 7460);
FORCEPROP 0 LASTPIN (-2550 7350) $PN 3
J 2
(-2560 7360);
DISPLAY 0.680851 (-2560 7360);
PAINT MONO (-2560 7360);
FORCEPROP 0 LASTPIN (-2200 7350) $PN 1
J 0
(-2190 7360);
DISPLAY 0.680851 (-2190 7360);
PAINT MONO (-2190 7360);
FORCEPROP 0 LASTPIN (-2550 7550) $PN 5
J 2
(-2560 7560);
DISPLAY 0.680851 (-2560 7560);
PAINT MONO (-2560 7560);
FORCEPROP 0 LASTPIN (-2200 7450) $PN 4
J 0
(-2190 7460);
DISPLAY 0.680851 (-2190 7460);
PAINT MONO (-2190 7460);
FORCEPROP 2 LAST PACK_TYPE SMLF
J 0
(-2500 7750);
DISPLAY 0.680851 (-2500 7750);
FORCEPROP 1 LAST MATERIAL IC
J 0
(-2500 7610);
DISPLAY 0.723404 (-2500 7610);
PAINT GREEN (-2500 7610);
FORCEPROP 2 LAST VALUE SN74LVC1G07DBVR
J 0
(-2500 7800);
DISPLAY 0.680851 (-2500 7800);
FORCEPROP 1 LAST NEEDS_NO_SIZE TRUE
J 0
(-2375 7450);
DISPLAY 0.468085 (-2375 7450);
PAINT GREEN (-2375 7450);
DISPLAY INVISIBLE (-2375 7450);
FORCEPROP 2 LAST CDS_LIB pure_quanta
J 0
(-2375 7450);
DISPLAY INVISIBLE (-2375 7450);
FORCEPROP 1 LAST PATH I51
J 0
(-2275 7605);
DISPLAY 0.723404 (-2275 7605);
PAINT GREEN (-2275 7605);
DISPLAY INVISIBLE (-2275 7605);
FORCEPROP 1 LAST PART_NUMBER AL1G0007024
J 0
(-2500 7660);
DISPLAY 0.723404 (-2500 7660);
PAINT GREEN (-2500 7660);
DISPLAY INVISIBLE (-2500 7660);
FORCEADD UNIVERSAL_POWER..1
R 2
(-3075 8200);
FORCEPROP 3 LASTPIN (-3075 8150) SIG_NAME P3V3_AUX\g
J 0
(-3065 8160);
DISPLAY 0.659574 (-3065 8160);
PAINT MONO (-3065 8160);
DISPLAY INVISIBLE (-3065 8160);
FORCEPROP 1 LAST HDL_POWER P3V3_AUX
J 1
(-3075 8250);
DISPLAY 0.723404 (-3075 8250);
PAINT GREEN (-3075 8250);
FORCEPROP 2 LAST CDS_LIB pure_quanta_power
J 0
(-3075 8200);
DISPLAY INVISIBLE (-3075 8200);
FORCEPROP 1 LAST PATH I52
J 2
(-3125 8225);
DISPLAY 0.872340 (-3125 8225);
PAINT AQUA (-3125 8225);
DISPLAY INVISIBLE (-3125 8225);
FORCEADD Q_CAP..1
R 2
(-3100 7875);
FORCEPROP 1 LAST LOCATION C1058
J 2
(-3150 8025);
DISPLAY 0.978723 (-3150 8025);
FORCEPROP 0 LAST $SEC 1
J 0
(-3150 8075);
DISPLAY 0.680851 (-3150 8075);
PAINT MONO (-3150 8075);
DISPLAY INVISIBLE (-3150 8075);
FORCEPROP 0 LAST CDS_SEC 1
J 0
(-3150 8075);
DISPLAY 0.680851 (-3150 8075);
DISPLAY INVISIBLE (-3150 8075);
FORCEPROP 1 LASTPIN (-3100 7975) $PN 1
J 2
(-3110 7955);
DISPLAY 0.787234 (-3110 7955);
PAINT MONO (-3110 7955);
FORCEPROP 1 LASTPIN (-3100 7775) $PN 2
J 2
(-3110 7755);
DISPLAY 0.787234 (-3110 7755);
PAINT MONO (-3110 7755);
FORCEPROP 1 LAST MATERIAL X7R
J 2
(-3150 7825);
DISPLAY 0.787234 (-3150 7825);
PAINT RED (-3150 7825);
FORCEPROP 1 LAST TOLERANCE 10%
J 2
(-3150 7875);
DISPLAY 0.787234 (-3150 7875);
FORCEPROP 1 LAST VOLTAGE 25V
J 2
(-3150 7925);
DISPLAY 0.787234 (-3150 7925);
FORCEPROP 1 LAST PACK_TYPE 0402
J 2
(-3150 7725);
DISPLAY 0.787234 (-3150 7725);
FORCEPROP 1 LAST VALUE 0.1UF
J 2
(-3150 7975);
DISPLAY 0.787234 (-3150 7975);
FORCEPROP 2 LAST CDS_LIB pure_quanta
J 2
(-3100 7875);
DISPLAY INVISIBLE (-3100 7875);
FORCEPROP 1 LAST PATH I53
J 2
(-3150 8025);
DISPLAY 0.978723 (-3150 8025);
PAINT WHITE (-3150 8025);
DISPLAY INVISIBLE (-3150 8025);
FORCEPROP 1 LAST PART_NUMBER CH4104K1B00
J 2
(-3150 7775);
DISPLAY 0.787234 (-3150 7775);
DISPLAY INVISIBLE (-3150 7775);
FORCEADD UNIVERSAL_GND..1
(-3100 7650);
FORCEPROP 3 LASTPIN (-3100 7700) SIG_NAME GND\g
J 0
(-3090 7710);
DISPLAY 0.659574 (-3090 7710);
PAINT MONO (-3090 7710);
DISPLAY INVISIBLE (-3090 7710);
FORCEPROP 2 LAST CDS_LIB pure_quanta_power
J 0
(-3100 7650);
DISPLAY INVISIBLE (-3100 7650);
FORCEPROP 1 LAST HDL_POWER GND
J 1
(-3075 7575);
DISPLAY 0.872340 (-3075 7575);
PAINT GREEN (-3075 7575);
DISPLAY INVISIBLE (-3075 7575);
FORCEPROP 1 LAST PATH I54
J 0
(-3025 7650);
DISPLAY 0.872340 (-3025 7650);
PAINT AQUA (-3025 7650);
DISPLAY INVISIBLE (-3025 7650);
FORCEADD UNIVERSAL_GND..1
(-2950 7250);
FORCEPROP 3 LASTPIN (-2950 7300) SIG_NAME GND\g
J 0
(-2940 7310);
DISPLAY 0.659574 (-2940 7310);
PAINT MONO (-2940 7310);
DISPLAY INVISIBLE (-2940 7310);
FORCEPROP 2 LAST CDS_LIB pure_quanta_power
J 0
(-2950 7250);
DISPLAY INVISIBLE (-2950 7250);
FORCEPROP 1 LAST HDL_POWER GND
J 1
(-2925 7175);
DISPLAY 0.872340 (-2925 7175);
PAINT GREEN (-2925 7175);
DISPLAY INVISIBLE (-2925 7175);
FORCEPROP 1 LAST PATH I55
J 0
(-2875 7250);
DISPLAY 0.872340 (-2875 7250);
PAINT AQUA (-2875 7250);
DISPLAY INVISIBLE (-2875 7250);
FORCEADD OFFPAGE..1
(-4875 7450);
PAINT AQUA (-4875 7450);
FORCEPROP 2 LAST $XR3 248 
J 0
(-5127 7414);
DISPLAY 0.638298 (-5127 7414);
PAINT MONO (-5127 7414);
FORCEPROP 2 LAST $XR2 136 
J 0
(-5367 7450);
DISPLAY 0.638298 (-5367 7450);
PAINT MONO (-5367 7450);
FORCEPROP 2 LAST $XR1 135 
J 0
(-5247 7450);
DISPLAY 0.638298 (-5247 7450);
PAINT MONO (-5247 7450);
FORCEPROP 2 LAST $XR0 134 
J 0
(-5127 7450);
DISPLAY 0.638298 (-5127 7450);
PAINT MONO (-5127 7450);
FORCEPROP 2 LAST CDS_LIB standard
J 0
(-4875 7450);
DISPLAY INVISIBLE (-4875 7450);
FORCEPROP 1 LAST OFFPAGE TRUE
J 0
(-4550 7325);
DISPLAY 0.872340 (-4550 7325);
PAINT AQUA (-4550 7325);
DISPLAY INVISIBLE (-4550 7325);
FORCEPROP 1 LAST COMMENT_BODY TRUE
J 0
(-4750 7350);
DISPLAY 0.872340 (-4750 7350);
PAINT GREEN (-4750 7350);
DISPLAY INVISIBLE (-4750 7350);
FORCEPROP 2 LAST PATH I56
J 0
(-4825 7525);
DISPLAY 0.680851 (-4825 7525);
DISPLAY INVISIBLE (-4825 7525);
FORCEADD Q_RES..1
(-3800 7450);
FORCEPROP 1 LAST LOCATION R1129
J 0
(-3850 7500);
DISPLAY 0.978723 (-3850 7500);
FORCEPROP 0 LAST $SEC 1
J 0
(-3850 7550);
DISPLAY 0.680851 (-3850 7550);
PAINT MONO (-3850 7550);
DISPLAY INVISIBLE (-3850 7550);
FORCEPROP 0 LAST CDS_SEC 1
J 0
(-3850 7550);
DISPLAY 0.680851 (-3850 7550);
DISPLAY INVISIBLE (-3850 7550);
FORCEPROP 1 LASTPIN (-3900 7450) $PN 1
J 0
(-3888 7462);
DISPLAY 0.787234 (-3888 7462);
PAINT MONO (-3888 7462);
FORCEPROP 1 LASTPIN (-3700 7450) $PN 2
J 0
(-3738 7462);
DISPLAY 0.787234 (-3738 7462);
PAINT MONO (-3738 7462);
FORCEPROP 1 LAST TOLERANCE 5%
J 0
(-3625 7450);
DISPLAY 0.510638 (-3625 7450);
FORCEPROP 1 LAST WATTAGE 1/16W
J 2
(-3600 7375);
DISPLAY 0.510638 (-3600 7375);
FORCEPROP 1 LAST PACK_TYPE 0402LF
J 0
(-3550 7450);
DISPLAY 0.510638 (-3550 7450);
FORCEPROP 1 LAST VALUE 0
J 2
(-3650 7450);
DISPLAY 0.510638 (-3650 7450);
FORCEPROP 1 LAST MATERIAL CHIP
J 0
(-3875 7375);
DISPLAY 0.510638 (-3875 7375);
PAINT RED (-3875 7375);
FORCEPROP 2 LAST CDS_LIB pure_quanta
J 0
(-3800 7450);
DISPLAY INVISIBLE (-3800 7450);
FORCEPROP 1 LAST PATH I57
J 0
(-3850 7600);
DISPLAY 0.978723 (-3850 7600);
PAINT WHITE (-3850 7600);
DISPLAY INVISIBLE (-3850 7600);
FORCEPROP 1 LAST PART_NUMBER CS00002JB13
J 0
(-3875 7400);
DISPLAY 0.510638 (-3875 7400);
DISPLAY INVISIBLE (-3875 7400);
FORCEADD Q_RES..1
(-1325 7450);
FORCEPROP 1 LAST LOCATION R1132
J 0
(-1375 7500);
DISPLAY 0.978723 (-1375 7500);
FORCEPROP 0 LAST $SEC 1
J 0
(-1375 7550);
DISPLAY 0.680851 (-1375 7550);
PAINT MONO (-1375 7550);
DISPLAY INVISIBLE (-1375 7550);
FORCEPROP 0 LAST CDS_SEC 1
J 0
(-1375 7550);
DISPLAY 0.680851 (-1375 7550);
DISPLAY INVISIBLE (-1375 7550);
FORCEPROP 1 LASTPIN (-1425 7450) $PN 1
J 0
(-1413 7462);
DISPLAY 0.787234 (-1413 7462);
PAINT MONO (-1413 7462);
FORCEPROP 1 LASTPIN (-1225 7450) $PN 2
J 0
(-1263 7462);
DISPLAY 0.787234 (-1263 7462);
PAINT MONO (-1263 7462);
FORCEPROP 1 LAST WATTAGE 1/16W
J 2
(-1125 7375);
DISPLAY 0.510638 (-1125 7375);
FORCEPROP 1 LAST VALUE 0
J 2
(-1175 7450);
DISPLAY 0.510638 (-1175 7450);
FORCEPROP 1 LAST PACK_TYPE 0402LF
J 0
(-1075 7450);
DISPLAY 0.510638 (-1075 7450);
FORCEPROP 1 LAST TOLERANCE 5%
J 0
(-1150 7450);
DISPLAY 0.510638 (-1150 7450);
FORCEPROP 1 LAST MATERIAL CHIP
J 0
(-1400 7375);
DISPLAY 0.510638 (-1400 7375);
PAINT RED (-1400 7375);
FORCEPROP 2 LAST CDS_LIB pure_quanta
J 0
(-1325 7450);
DISPLAY INVISIBLE (-1325 7450);
FORCEPROP 1 LAST PATH I58
J 0
(-1375 7600);
DISPLAY 0.978723 (-1375 7600);
PAINT WHITE (-1375 7600);
DISPLAY INVISIBLE (-1375 7600);
FORCEPROP 1 LAST PART_NUMBER CS00002JB13
J 0
(-1400 7400);
DISPLAY 0.510638 (-1400 7400);
DISPLAY INVISIBLE (-1400 7400);
FORCEADD OFFPAGE..2
(-150 7450);
PAINT AQUA (-150 7450);
FORCEPROP 2 LAST $XR0 82 
J 0
(39 7450);
DISPLAY 0.638298 (39 7450);
PAINT MONO (39 7450);
FORCEPROP 2 LAST CDS_LIB standard
J 0
(-150 7450);
DISPLAY INVISIBLE (-150 7450);
FORCEPROP 1 LAST OFFPAGE TRUE
J 0
(175 7325);
DISPLAY 0.872340 (175 7325);
PAINT AQUA (175 7325);
DISPLAY INVISIBLE (175 7325);
FORCEPROP 1 LAST COMMENT_BODY TRUE
J 0
(-195 7355);
DISPLAY 0.872340 (-195 7355);
PAINT GREEN (-195 7355);
DISPLAY INVISIBLE (-195 7355);
FORCEPROP 2 LAST PATH I59
J 0
(25 7525);
DISPLAY 0.680851 (25 7525);
DISPLAY INVISIBLE (25 7525);
FORCEADD UNIVERSAL_POWER..1
R 2
(-875 8050);
FORCEPROP 3 LASTPIN (-875 8000) SIG_NAME P3V3_AUX\g
J 0
(-865 8010);
DISPLAY 0.659574 (-865 8010);
PAINT MONO (-865 8010);
DISPLAY INVISIBLE (-865 8010);
FORCEPROP 1 LAST HDL_POWER P3V3_AUX
J 1
(-875 8100);
DISPLAY 0.723404 (-875 8100);
PAINT GREEN (-875 8100);
FORCEPROP 2 LAST CDS_LIB pure_quanta_power
J 0
(-875 8050);
DISPLAY INVISIBLE (-875 8050);
FORCEPROP 1 LAST PATH I60
J 2
(-925 8075);
DISPLAY 0.872340 (-925 8075);
PAINT AQUA (-925 8075);
DISPLAY INVISIBLE (-925 8075);
FORCEADD Q_RES..2
R 2
(-875 7800);
FORCEPROP 1 LAST LOCATION R1133
J 2
(-920 7925);
DISPLAY 0.638298 (-920 7925);
FORCEPROP 0 LAST $SEC 1
J 0
(-900 7975);
DISPLAY 0.680851 (-900 7975);
PAINT MONO (-900 7975);
DISPLAY INVISIBLE (-900 7975);
FORCEPROP 0 LAST CDS_SEC 1
J 0
(-900 7975);
DISPLAY 0.680851 (-900 7975);
DISPLAY INVISIBLE (-900 7975);
FORCEPROP 1 LASTPIN (-875 7900) $PN 1
J 2
(-880 7862);
DISPLAY 0.787234 (-880 7862);
PAINT MONO (-880 7862);
FORCEPROP 1 LASTPIN (-875 7700) $PN 2
J 2
(-880 7710);
DISPLAY 0.787234 (-880 7710);
PAINT MONO (-880 7710);
FORCEPROP 1 LAST VALUE 1K
J 2
(-920 7875);
DISPLAY 0.638298 (-920 7875);
FORCEPROP 1 LAST TOLERANCE 1%
J 2
(-920 7825);
DISPLAY 0.638298 (-920 7825);
FORCEPROP 1 LAST MATERIAL CHIP
J 2
(-915 7725);
DISPLAY 0.638298 (-915 7725);
FORCEPROP 1 LAST WATTAGE 1/16W
J 2
(-915 7775);
DISPLAY 0.638298 (-915 7775);
FORCEPROP 1 LAST PACK_TYPE 0402LF
J 2
(-915 7625);
DISPLAY 0.638298 (-915 7625);
FORCEPROP 2 LAST CDS_LIB pure_quanta
J 0
(-875 7800);
DISPLAY INVISIBLE (-875 7800);
FORCEPROP 1 LAST PATH I61
J 2
(-925 7975);
DISPLAY 0.978723 (-925 7975);
PAINT WHITE (-925 7975);
DISPLAY INVISIBLE (-925 7975);
FORCEPROP 1 LAST PART_NUMBER CS21002FB06
J 2
(-915 7675);
DISPLAY 0.638298 (-915 7675);
DISPLAY INVISIBLE (-915 7675);
FORCEADD OFFPAGE..2
(3400 8225);
PAINT AQUA (3400 8225);
FORCEPROP 2 LAST $XR0 80 
J 0
(3589 8225);
DISPLAY 0.638298 (3589 8225);
PAINT MONO (3589 8225);
FORCEPROP 2 LAST CDS_LIB standard
J 0
(3400 8225);
DISPLAY INVISIBLE (3400 8225);
FORCEPROP 1 LAST OFFPAGE TRUE
J 0
(3725 8100);
DISPLAY 0.872340 (3725 8100);
PAINT AQUA (3725 8100);
DISPLAY INVISIBLE (3725 8100);
FORCEPROP 1 LAST COMMENT_BODY TRUE
J 0
(3355 8130);
DISPLAY 0.872340 (3355 8130);
PAINT GREEN (3355 8130);
DISPLAY INVISIBLE (3355 8130);
FORCEPROP 2 LAST PATH I62
J 0
(3575 8300);
DISPLAY 0.680851 (3575 8300);
DISPLAY INVISIBLE (3575 8300);
FORCEADD UNIVERSAL_POWER..1
R 2
(2475 8825);
FORCEPROP 3 LASTPIN (2475 8775) SIG_NAME P3V3_AUX\g
J 0
(2485 8785);
DISPLAY 0.659574 (2485 8785);
PAINT MONO (2485 8785);
DISPLAY INVISIBLE (2485 8785);
FORCEPROP 1 LAST HDL_POWER P3V3_AUX
J 1
(2475 8875);
DISPLAY 0.723404 (2475 8875);
PAINT GREEN (2475 8875);
FORCEPROP 2 LAST CDS_LIB pure_quanta_power
J 0
(2475 8825);
DISPLAY INVISIBLE (2475 8825);
FORCEPROP 1 LAST PATH I63
J 2
(2425 8850);
DISPLAY 0.872340 (2425 8850);
PAINT AQUA (2425 8850);
DISPLAY INVISIBLE (2425 8850);
FORCEADD Q_RES..2
R 2
(2475 8575);
FORCEPROP 1 LAST LOCATION R1144
J 2
(2430 8700);
DISPLAY 0.638298 (2430 8700);
FORCEPROP 0 LAST $SEC 1
J 0
(2450 8750);
DISPLAY 0.680851 (2450 8750);
PAINT MONO (2450 8750);
DISPLAY INVISIBLE (2450 8750);
FORCEPROP 0 LAST CDS_SEC 1
J 0
(2450 8750);
DISPLAY 0.680851 (2450 8750);
DISPLAY INVISIBLE (2450 8750);
FORCEPROP 1 LASTPIN (2475 8675) $PN 1
J 2
(2470 8637);
DISPLAY 0.787234 (2470 8637);
PAINT MONO (2470 8637);
FORCEPROP 1 LASTPIN (2475 8475) $PN 2
J 2
(2470 8485);
DISPLAY 0.787234 (2470 8485);
PAINT MONO (2470 8485);
FORCEPROP 1 LAST VALUE 1K
J 2
(2430 8650);
DISPLAY 0.638298 (2430 8650);
FORCEPROP 1 LAST TOLERANCE 1%
J 2
(2430 8600);
DISPLAY 0.638298 (2430 8600);
FORCEPROP 1 LAST MATERIAL CHIP
J 2
(2435 8500);
DISPLAY 0.638298 (2435 8500);
FORCEPROP 1 LAST WATTAGE 1/16W
J 2
(2435 8550);
DISPLAY 0.638298 (2435 8550);
FORCEPROP 1 LAST PACK_TYPE 0402LF
J 2
(2435 8400);
DISPLAY 0.638298 (2435 8400);
FORCEPROP 2 LAST CDS_LIB pure_quanta
J 0
(2475 8575);
DISPLAY INVISIBLE (2475 8575);
FORCEPROP 1 LAST PATH I64
J 2
(2425 8750);
DISPLAY 0.978723 (2425 8750);
PAINT WHITE (2425 8750);
DISPLAY INVISIBLE (2425 8750);
FORCEPROP 1 LAST PART_NUMBER CS21002FB06
J 2
(2435 8450);
DISPLAY 0.638298 (2435 8450);
DISPLAY INVISIBLE (2435 8450);
FORCEADD Q_RES..1
(1975 8225);
FORCEPROP 1 LAST LOCATION R1143
J 0
(1925 8275);
DISPLAY 0.978723 (1925 8275);
FORCEPROP 0 LAST $SEC 1
J 0
(1925 8325);
DISPLAY 0.680851 (1925 8325);
PAINT MONO (1925 8325);
DISPLAY INVISIBLE (1925 8325);
FORCEPROP 0 LAST CDS_SEC 1
J 0
(1925 8325);
DISPLAY 0.680851 (1925 8325);
DISPLAY INVISIBLE (1925 8325);
FORCEPROP 1 LASTPIN (1875 8225) $PN 1
J 0
(1887 8237);
DISPLAY 0.787234 (1887 8237);
PAINT MONO (1887 8237);
FORCEPROP 1 LASTPIN (2075 8225) $PN 2
J 0
(2037 8237);
DISPLAY 0.787234 (2037 8237);
PAINT MONO (2037 8237);
FORCEPROP 1 LAST MATERIAL CHIP
J 0
(1900 8150);
DISPLAY 0.510638 (1900 8150);
PAINT RED (1900 8150);
FORCEPROP 1 LAST VALUE 0
J 2
(2125 8225);
DISPLAY 0.510638 (2125 8225);
FORCEPROP 1 LAST TOLERANCE 5%
J 0
(2150 8225);
DISPLAY 0.510638 (2150 8225);
FORCEPROP 1 LAST WATTAGE 1/16W
J 2
(2175 8150);
DISPLAY 0.510638 (2175 8150);
FORCEPROP 1 LAST PACK_TYPE 0402LF
J 0
(2225 8225);
DISPLAY 0.510638 (2225 8225);
FORCEPROP 2 LAST CDS_LIB pure_quanta
J 0
(1975 8225);
DISPLAY INVISIBLE (1975 8225);
FORCEPROP 1 LAST PATH I65
J 0
(1925 8375);
DISPLAY 0.978723 (1925 8375);
PAINT WHITE (1925 8375);
DISPLAY INVISIBLE (1925 8375);
FORCEPROP 1 LAST PART_NUMBER CS00002JB13
J 0
(1900 8175);
DISPLAY 0.510638 (1900 8175);
DISPLAY INVISIBLE (1900 8175);
FORCEADD SN74LVC1G07DBVR..1
(900 8225);
FORCEPROP 1 LAST LOCATION U30
J 0
(775 8480);
DISPLAY 0.723404 (775 8480);
PAINT GREEN (775 8480);
FORCEPROP 0 LAST $SEC 1
J 0
(775 8625);
DISPLAY 0.680851 (775 8625);
PAINT MONO (775 8625);
DISPLAY INVISIBLE (775 8625);
FORCEPROP 0 LAST CDS_SEC 1
J 0
(775 8625);
DISPLAY 0.680851 (775 8625);
DISPLAY INVISIBLE (775 8625);
FORCEPROP 0 LASTPIN (725 8225) $PN 2
J 2
(715 8235);
DISPLAY 0.680851 (715 8235);
PAINT MONO (715 8235);
FORCEPROP 0 LASTPIN (725 8125) $PN 3
J 2
(715 8135);
DISPLAY 0.680851 (715 8135);
PAINT MONO (715 8135);
FORCEPROP 0 LASTPIN (1075 8125) $PN 1
J 0
(1085 8135);
DISPLAY 0.680851 (1085 8135);
PAINT MONO (1085 8135);
FORCEPROP 0 LASTPIN (725 8325) $PN 5
J 2
(715 8335);
DISPLAY 0.680851 (715 8335);
PAINT MONO (715 8335);
FORCEPROP 0 LASTPIN (1075 8225) $PN 4
J 0
(1085 8235);
DISPLAY 0.680851 (1085 8235);
PAINT MONO (1085 8235);
FORCEPROP 2 LAST VALUE SN74LVC1G07DBVR
J 0
(775 8575);
DISPLAY 0.680851 (775 8575);
FORCEPROP 2 LAST PACK_TYPE SMLF
J 0
(775 8525);
DISPLAY 0.680851 (775 8525);
FORCEPROP 1 LAST MATERIAL IC
J 0
(775 8385);
DISPLAY 0.723404 (775 8385);
PAINT GREEN (775 8385);
FORCEPROP 1 LAST NEEDS_NO_SIZE TRUE
J 0
(900 8225);
DISPLAY 0.468085 (900 8225);
PAINT GREEN (900 8225);
DISPLAY INVISIBLE (900 8225);
FORCEPROP 2 LAST CDS_LIB pure_quanta
J 0
(900 8225);
DISPLAY INVISIBLE (900 8225);
FORCEPROP 1 LAST PATH I66
J 0
(1000 8380);
DISPLAY 0.723404 (1000 8380);
PAINT GREEN (1000 8380);
DISPLAY INVISIBLE (1000 8380);
FORCEPROP 1 LAST PART_NUMBER AL1G0007024
J 0
(775 8435);
DISPLAY 0.723404 (775 8435);
PAINT GREEN (775 8435);
DISPLAY INVISIBLE (775 8435);
FORCEADD UNIVERSAL_GND..1
(325 8025);
FORCEPROP 3 LASTPIN (325 8075) SIG_NAME GND\g
J 0
(335 8085);
DISPLAY 0.659574 (335 8085);
PAINT MONO (335 8085);
DISPLAY INVISIBLE (335 8085);
FORCEPROP 2 LAST CDS_LIB pure_quanta_power
J 0
(325 8025);
DISPLAY INVISIBLE (325 8025);
FORCEPROP 1 LAST HDL_POWER GND
J 1
(350 7950);
DISPLAY 0.872340 (350 7950);
PAINT GREEN (350 7950);
DISPLAY INVISIBLE (350 7950);
FORCEPROP 1 LAST PATH I67
J 0
(400 8025);
DISPLAY 0.872340 (400 8025);
PAINT AQUA (400 8025);
DISPLAY INVISIBLE (400 8025);
FORCEADD UNIVERSAL_POWER..1
R 2
(200 8975);
FORCEPROP 3 LASTPIN (200 8925) SIG_NAME P3V3_AUX\g
J 0
(210 8935);
DISPLAY 0.659574 (210 8935);
PAINT MONO (210 8935);
DISPLAY INVISIBLE (210 8935);
FORCEPROP 1 LAST HDL_POWER P3V3_AUX
J 1
(200 9025);
DISPLAY 0.723404 (200 9025);
PAINT GREEN (200 9025);
FORCEPROP 2 LAST CDS_LIB pure_quanta_power
J 0
(200 8975);
DISPLAY INVISIBLE (200 8975);
FORCEPROP 1 LAST PATH I68
J 2
(150 9000);
DISPLAY 0.872340 (150 9000);
PAINT AQUA (150 9000);
DISPLAY INVISIBLE (150 9000);
FORCEADD Q_CAP..1
R 2
(175 8650);
FORCEPROP 1 LAST LOCATION C1060
J 2
(125 8800);
DISPLAY 0.978723 (125 8800);
FORCEPROP 0 LAST $SEC 1
J 0
(125 8850);
DISPLAY 0.680851 (125 8850);
PAINT MONO (125 8850);
DISPLAY INVISIBLE (125 8850);
FORCEPROP 0 LAST CDS_SEC 1
J 0
(125 8850);
DISPLAY 0.680851 (125 8850);
DISPLAY INVISIBLE (125 8850);
FORCEPROP 1 LASTPIN (175 8750) $PN 1
J 2
(165 8730);
DISPLAY 0.787234 (165 8730);
PAINT MONO (165 8730);
FORCEPROP 1 LASTPIN (175 8550) $PN 2
J 2
(165 8530);
DISPLAY 0.787234 (165 8530);
PAINT MONO (165 8530);
FORCEPROP 1 LAST TOLERANCE 10%
J 2
(125 8650);
DISPLAY 0.787234 (125 8650);
FORCEPROP 1 LAST PACK_TYPE 0402
J 2
(125 8500);
DISPLAY 0.787234 (125 8500);
FORCEPROP 1 LAST VOLTAGE 25V
J 2
(125 8700);
DISPLAY 0.787234 (125 8700);
FORCEPROP 1 LAST MATERIAL X7R
J 2
(125 8600);
DISPLAY 0.787234 (125 8600);
PAINT RED (125 8600);
FORCEPROP 1 LAST VALUE 0.1UF
J 2
(125 8750);
DISPLAY 0.787234 (125 8750);
FORCEPROP 2 LAST CDS_LIB pure_quanta
J 0
(175 8650);
DISPLAY INVISIBLE (175 8650);
FORCEPROP 1 LAST PATH I69
J 2
(125 8800);
DISPLAY 0.978723 (125 8800);
PAINT WHITE (125 8800);
DISPLAY INVISIBLE (125 8800);
FORCEPROP 1 LAST PART_NUMBER CH4104K1B00
J 2
(125 8550);
DISPLAY 0.787234 (125 8550);
DISPLAY INVISIBLE (125 8550);
FORCEADD UNIVERSAL_GND..1
(175 8425);
FORCEPROP 3 LASTPIN (175 8475) SIG_NAME GND\g
J 0
(185 8485);
DISPLAY 0.659574 (185 8485);
PAINT MONO (185 8485);
DISPLAY INVISIBLE (185 8485);
FORCEPROP 2 LAST CDS_LIB pure_quanta_power
J 0
(175 8425);
DISPLAY INVISIBLE (175 8425);
FORCEPROP 1 LAST HDL_POWER GND
J 1
(200 8350);
DISPLAY 0.872340 (200 8350);
PAINT GREEN (200 8350);
DISPLAY INVISIBLE (200 8350);
FORCEPROP 1 LAST PATH I70
J 0
(250 8425);
DISPLAY 0.872340 (250 8425);
PAINT AQUA (250 8425);
DISPLAY INVISIBLE (250 8425);
FORCEADD Q_RES..1
(-450 8225);
FORCEPROP 1 LAST LOCATION R1142
J 0
(-500 8275);
DISPLAY 0.978723 (-500 8275);
FORCEPROP 0 LAST $SEC 1
J 0
(-500 8325);
DISPLAY 0.680851 (-500 8325);
PAINT MONO (-500 8325);
DISPLAY INVISIBLE (-500 8325);
FORCEPROP 0 LAST CDS_SEC 1
J 0
(-500 8325);
DISPLAY 0.680851 (-500 8325);
DISPLAY INVISIBLE (-500 8325);
FORCEPROP 1 LASTPIN (-550 8225) $PN 1
J 0
(-538 8237);
DISPLAY 0.787234 (-538 8237);
PAINT MONO (-538 8237);
FORCEPROP 1 LASTPIN (-350 8225) $PN 2
J 0
(-388 8237);
DISPLAY 0.787234 (-388 8237);
PAINT MONO (-388 8237);
FORCEPROP 1 LAST WATTAGE 1/16W
J 2
(-250 8150);
DISPLAY 0.510638 (-250 8150);
FORCEPROP 1 LAST MATERIAL CHIP
J 0
(-525 8150);
DISPLAY 0.510638 (-525 8150);
PAINT RED (-525 8150);
FORCEPROP 1 LAST PACK_TYPE 0402LF
J 0
(-200 8225);
DISPLAY 0.510638 (-200 8225);
FORCEPROP 1 LAST VALUE 0
J 2
(-300 8225);
DISPLAY 0.510638 (-300 8225);
FORCEPROP 1 LAST TOLERANCE 5%
J 0
(-275 8225);
DISPLAY 0.510638 (-275 8225);
FORCEPROP 2 LAST CDS_LIB pure_quanta
J 0
(-450 8225);
DISPLAY INVISIBLE (-450 8225);
FORCEPROP 1 LAST PATH I71
J 0
(-500 8375);
DISPLAY 0.978723 (-500 8375);
PAINT WHITE (-500 8375);
DISPLAY INVISIBLE (-500 8375);
FORCEPROP 1 LAST PART_NUMBER CS00002JB13
J 0
(-525 8175);
DISPLAY 0.510638 (-525 8175);
DISPLAY INVISIBLE (-525 8175);
FORCEADD OFFPAGE..1
(-1250 8225);
PAINT AQUA (-1250 8225);
FORCEPROP 2 LAST $XR1 136 
J 0
(-1652 8225);
DISPLAY 0.638298 (-1652 8225);
PAINT MONO (-1652 8225);
FORCEPROP 2 LAST $XR0 134 
J 0
(-1532 8225);
DISPLAY 0.638298 (-1532 8225);
PAINT MONO (-1532 8225);
FORCEPROP 2 LAST CDS_LIB standard
J 0
(-1250 8225);
DISPLAY INVISIBLE (-1250 8225);
FORCEPROP 1 LAST OFFPAGE TRUE
J 0
(-925 8100);
DISPLAY 0.872340 (-925 8100);
PAINT AQUA (-925 8100);
DISPLAY INVISIBLE (-925 8100);
FORCEPROP 1 LAST COMMENT_BODY TRUE
J 0
(-1125 8125);
DISPLAY 0.872340 (-1125 8125);
PAINT GREEN (-1125 8125);
DISPLAY INVISIBLE (-1125 8125);
FORCEPROP 2 LAST PATH I72
J 0
(-1200 8300);
DISPLAY 0.680851 (-1200 8300);
DISPLAY INVISIBLE (-1200 8300);
FORCEADD OFFPAGE..1
(-2675 6600);
PAINT AQUA (-2675 6600);
FORCEPROP 2 LAST $XR1 136 
J 0
(-3047 6600);
DISPLAY 0.638298 (-3047 6600);
PAINT MONO (-3047 6600);
FORCEPROP 2 LAST $XR0 134 
J 0
(-2927 6600);
DISPLAY 0.638298 (-2927 6600);
PAINT MONO (-2927 6600);
FORCEPROP 2 LAST CDS_LIB standard
J 0
(-2675 6600);
DISPLAY INVISIBLE (-2675 6600);
FORCEPROP 1 LAST OFFPAGE TRUE
J 0
(-2350 6475);
DISPLAY 0.872340 (-2350 6475);
PAINT AQUA (-2350 6475);
DISPLAY INVISIBLE (-2350 6475);
FORCEPROP 1 LAST COMMENT_BODY TRUE
J 0
(-2550 6500);
DISPLAY 0.872340 (-2550 6500);
PAINT GREEN (-2550 6500);
DISPLAY INVISIBLE (-2550 6500);
FORCEPROP 2 LAST PATH I73
J 0
(-2625 6675);
DISPLAY 0.680851 (-2625 6675);
DISPLAY INVISIBLE (-2625 6675);
FORCEADD 74LVC1G32GW..1
(425 5375);
FORCEPROP 1 LAST LOCATION U9002
J 0
(275 5630);
DISPLAY 0.723404 (275 5630);
PAINT GREEN (275 5630);
FORCEPROP 0 LAST $SEC 1
J 0
(275 5775);
DISPLAY 0.680851 (275 5775);
PAINT MONO (275 5775);
DISPLAY INVISIBLE (275 5775);
FORCEPROP 0 LAST CDS_SEC 1
J 0
(275 5775);
DISPLAY 0.680851 (275 5775);
DISPLAY INVISIBLE (275 5775);
FORCEPROP 0 LASTPIN (225 5275) $PN 3
J 2
(215 5285);
DISPLAY 0.680851 (215 5285);
PAINT MONO (215 5285);
FORCEPROP 0 LASTPIN (125 5425) $PN 1
J 2
(115 5435);
DISPLAY 0.680851 (115 5435);
PAINT MONO (115 5435);
FORCEPROP 0 LASTPIN (125 5325) $PN 2
J 2
(115 5335);
DISPLAY 0.680851 (115 5335);
PAINT MONO (115 5335);
FORCEPROP 0 LASTPIN (725 5375) $PN 4
J 0
(735 5385);
DISPLAY 0.680851 (735 5385);
PAINT MONO (735 5385);
FORCEPROP 0 LASTPIN (225 5475) $PN 5
J 2
(215 5485);
DISPLAY 0.680851 (215 5485);
PAINT MONO (215 5485);
FORCEPROP 2 LAST VALUE 74LVC1G32GW
J 0
(275 5725);
DISPLAY 0.680851 (275 5725);
FORCEPROP 2 LAST PACK_TYPE SMLF
J 0
(275 5675);
DISPLAY 0.680851 (275 5675);
FORCEPROP 1 LAST MATERIAL IC
J 0
(275 5510);
DISPLAY 0.723404 (275 5510);
PAINT GREEN (275 5510);
FORCEPROP 2 LAST CDS_LIB pure_quanta
J 0
(425 5375);
DISPLAY INVISIBLE (425 5375);
FORCEPROP 1 LAST NEEDS_NO_SIZE TRUE
J 0
(425 5375);
DISPLAY 0.468085 (425 5375);
PAINT GREEN (425 5375);
DISPLAY INVISIBLE (425 5375);
FORCEPROP 1 LAST PATH I74
J 0
(450 5505);
DISPLAY 0.723404 (450 5505);
PAINT GREEN (450 5505);
DISPLAY INVISIBLE (450 5505);
FORCEPROP 1 LAST PART_NUMBER ALVC1G32007
J 0
(275 5560);
DISPLAY 0.723404 (275 5560);
PAINT GREEN (275 5560);
DISPLAY INVISIBLE (275 5560);
FORCEADD Q_CAP..1
R 2
(-50 5700);
FORCEPROP 1 LAST LOCATION C9008
J 2
(-100 5800);
DISPLAY 0.638298 (-100 5800);
FORCEPROP 0 LAST $SEC 1
J 2
(-100 5850);
DISPLAY 0.680851 (-100 5850);
PAINT MONO (-100 5850);
DISPLAY INVISIBLE (-100 5850);
FORCEPROP 0 LAST CDS_SEC 1
J 2
(-100 5850);
DISPLAY 0.680851 (-100 5850);
DISPLAY INVISIBLE (-100 5850);
FORCEPROP 1 LASTPIN (-50 5800) $PN 1
J 2
(-60 5780);
DISPLAY 0.787234 (-60 5780);
PAINT MONO (-60 5780);
FORCEPROP 1 LASTPIN (-50 5600) $PN 2
J 2
(-60 5580);
DISPLAY 0.787234 (-60 5580);
PAINT MONO (-60 5580);
FORCEPROP 1 LAST MATERIAL X7R
J 2
(-100 5600);
DISPLAY 0.510638 (-100 5600);
PAINT RED (-100 5600);
FORCEPROP 1 LAST VOLTAGE 25V
J 2
(-100 5700);
DISPLAY 0.510638 (-100 5700);
FORCEPROP 1 LAST TOLERANCE 10%
J 2
(-100 5650);
DISPLAY 0.510638 (-100 5650);
FORCEPROP 1 LAST VALUE 0.1UF
J 2
(-100 5750);
DISPLAY 0.510638 (-100 5750);
FORCEPROP 1 LAST PACK_TYPE 0402
J 2
(-100 5500);
DISPLAY 0.510638 (-100 5500);
FORCEPROP 2 LAST CDS_LIB pure_quanta
J 2
(-50 5700);
DISPLAY INVISIBLE (-50 5700);
FORCEPROP 1 LAST PATH I75
J 2
(-100 5850);
DISPLAY 0.978723 (-100 5850);
PAINT WHITE (-100 5850);
DISPLAY INVISIBLE (-100 5850);
FORCEPROP 1 LAST PART_NUMBER CH4104K1B00
J 2
(-100 5550);
DISPLAY 0.510638 (-100 5550);
DISPLAY INVISIBLE (-100 5550);
FORCEADD Q_RES..2
(2700 5850);
FORCEPROP 1 LAST LOCATION R1145
J 0
(2745 5975);
DISPLAY 0.978723 (2745 5975);
FORCEPROP 0 LAST $SEC 1
J 0
(2750 6025);
DISPLAY 0.680851 (2750 6025);
PAINT MONO (2750 6025);
DISPLAY INVISIBLE (2750 6025);
FORCEPROP 0 LAST CDS_SEC 1
J 0
(2750 6025);
DISPLAY 0.680851 (2750 6025);
DISPLAY INVISIBLE (2750 6025);
FORCEPROP 1 LASTPIN (2700 5950) $PN 1
J 0
(2705 5912);
DISPLAY 0.787234 (2705 5912);
PAINT MONO (2705 5912);
FORCEPROP 1 LASTPIN (2700 5750) $PN 2
J 0
(2705 5760);
DISPLAY 0.787234 (2705 5760);
PAINT MONO (2705 5760);
FORCEPROP 1 LAST VALUE 10K
J 0
(2745 5925);
DISPLAY 0.978723 (2745 5925);
FORCEPROP 1 LAST PACK_TYPE 0402LF
J 0
(2740 5675);
DISPLAY 0.978723 (2740 5675);
FORCEPROP 1 LAST MATERIAL EMPTY
J 0
(2740 5775);
DISPLAY 0.978723 (2740 5775);
PAINT RED (2740 5775);
FORCEPROP 1 LAST WATTAGE 1/16W
J 0
(2740 5825);
DISPLAY 0.978723 (2740 5825);
FORCEPROP 1 LAST TOLERANCE 5%
J 0
(2745 5875);
DISPLAY 0.978723 (2745 5875);
FORCEPROP 2 LAST CDS_LIB pure_quanta
J 0
(2700 5850);
DISPLAY INVISIBLE (2700 5850);
FORCEPROP 1 LAST PATH I76
J 0
(2750 6025);
DISPLAY 0.978723 (2750 6025);
PAINT WHITE (2750 6025);
DISPLAY INVISIBLE (2750 6025);
FORCEPROP 1 LAST PART_NUMBER CS31002JB08
J 0
(2740 5725);
DISPLAY 0.978723 (2740 5725);
DISPLAY INVISIBLE (2740 5725);
FORCEADD UNIVERSAL_POWER..1
R 2
(2700 6100);
FORCEPROP 3 LASTPIN (2700 6050) SIG_NAME P3V3_AUX\g
J 0
(2710 6060);
DISPLAY 0.659574 (2710 6060);
PAINT MONO (2710 6060);
DISPLAY INVISIBLE (2710 6060);
FORCEPROP 1 LAST HDL_POWER P3V3_AUX
J 1
(2700 6150);
DISPLAY 0.723404 (2700 6150);
PAINT GREEN (2700 6150);
FORCEPROP 2 LAST CDS_LIB pure_quanta_power
J 0
(2700 6100);
DISPLAY INVISIBLE (2700 6100);
FORCEPROP 1 LAST PATH I77
J 2
(2650 6125);
DISPLAY 0.872340 (2650 6125);
PAINT AQUA (2650 6125);
DISPLAY INVISIBLE (2650 6125);
FORCEADD UNIVERSAL_GND..1
(-4825 4100);
FORCEPROP 3 LASTPIN (-4825 4150) SIG_NAME GND\g
J 0
(-4815 4160);
DISPLAY 0.659574 (-4815 4160);
PAINT MONO (-4815 4160);
DISPLAY INVISIBLE (-4815 4160);
FORCEPROP 2 LAST CDS_LIB pure_quanta_power
J 0
(-4825 4100);
DISPLAY INVISIBLE (-4825 4100);
FORCEPROP 1 LAST HDL_POWER GND
J 1
(-4800 4025);
DISPLAY 0.872340 (-4800 4025);
PAINT GREEN (-4800 4025);
DISPLAY INVISIBLE (-4800 4025);
FORCEPROP 1 LAST PATH I78
J 0
(-4750 4100);
DISPLAY 0.872340 (-4750 4100);
PAINT AQUA (-4750 4100);
DISPLAY INVISIBLE (-4750 4100);
FORCEADD Q_CAP..1
R 2
(-4825 4425);
FORCEPROP 1 LAST LOCATION C8008
J 2
(-4875 4525);
DISPLAY 0.787234 (-4875 4525);
FORCEPROP 0 LAST $SEC 1
J 0
(-4875 4575);
DISPLAY 0.680851 (-4875 4575);
PAINT MONO (-4875 4575);
DISPLAY INVISIBLE (-4875 4575);
FORCEPROP 0 LAST CDS_SEC 1
J 0
(-4875 4575);
DISPLAY 0.680851 (-4875 4575);
DISPLAY INVISIBLE (-4875 4575);
FORCEPROP 1 LASTPIN (-4825 4525) $PN 1
J 2
(-4835 4505);
DISPLAY 0.787234 (-4835 4505);
PAINT MONO (-4835 4505);
FORCEPROP 1 LASTPIN (-4825 4325) $PN 2
J 2
(-4835 4305);
DISPLAY 0.787234 (-4835 4305);
PAINT MONO (-4835 4305);
FORCEPROP 1 LAST MATERIAL X7R
J 2
(-4875 4325);
DISPLAY 0.787234 (-4875 4325);
PAINT RED (-4875 4325);
FORCEPROP 1 LAST TOLERANCE 10%
J 2
(-4875 4375);
DISPLAY 0.787234 (-4875 4375);
FORCEPROP 1 LAST PACK_TYPE 0402
J 2
(-4875 4225);
DISPLAY 0.787234 (-4875 4225);
FORCEPROP 1 LAST VOLTAGE 25V
J 2
(-4875 4425);
DISPLAY 0.787234 (-4875 4425);
FORCEPROP 1 LAST VALUE 0.1UF
J 2
(-4875 4475);
DISPLAY 0.787234 (-4875 4475);
FORCEPROP 2 LAST CDS_LIB pure_quanta
J 2
(-4825 4425);
DISPLAY INVISIBLE (-4825 4425);
FORCEPROP 1 LAST PATH I79
J 2
(-4875 4575);
DISPLAY 0.978723 (-4875 4575);
PAINT WHITE (-4875 4575);
DISPLAY INVISIBLE (-4875 4575);
FORCEPROP 1 LAST PART_NUMBER CH4104K1B00
J 2
(-4875 4275);
DISPLAY 0.787234 (-4875 4275);
DISPLAY INVISIBLE (-4875 4275);
FORCEADD APX80929SAG7..1
R 2
(-4250 4675);
FORCEPROP 1 LAST LOCATION U8001
J 2
(-4025 4994);
DISPLAY 0.723404 (-4025 4994);
PAINT GREEN (-4025 4994);
FORCEPROP 2 LAST SEC 1
J 0
(-4025 5150);
DISPLAY 0.680851 (-4025 5150);
PAINT MONO (-4025 5150);
DISPLAY INVISIBLE (-4025 5150);
FORCEPROP 2 LASTPIN (-3875 4775) $PN 1
J 0
(-3865 4785);
DISPLAY 0.680851 (-3865 4785);
PAINT MONO (-3865 4785);
FORCEPROP 2 LASTPIN (-3875 4575) $PN 2
J 0
(-3865 4585);
DISPLAY 0.680851 (-3865 4585);
PAINT MONO (-3865 4585);
FORCEPROP 2 LASTPIN (-4625 4675) $PN 3
J 2
(-4635 4685);
DISPLAY 0.680851 (-4635 4685);
PAINT MONO (-4635 4685);
FORCEPROP 1 LAST MATERIAL IC
J 2
(-4025 4885);
DISPLAY 0.723404 (-4025 4885);
PAINT GREEN (-4025 4885);
FORCEPROP 2 LAST VALUE APX809-29SAG-7
J 2
(-4025 5050);
DISPLAY 0.680851 (-4025 5050);
FORCEPROP 2 LAST PART_TYPE SMLF
J 2
(-4025 5100);
DISPLAY 0.680851 (-4025 5100);
FORCEPROP 1 LAST CDS_LMAN_SYM_OUTLINE -225,200,225,-200
J 2
(-4250 4675);
DISPLAY 0.468085 (-4250 4675);
PAINT GREEN (-4250 4675);
DISPLAY INVISIBLE (-4250 4675);
FORCEPROP 1 LAST NEEDS_NO_SIZE TRUE
J 2
(-4475 4515);
DISPLAY 0.723404 (-4475 4515);
PAINT GREEN (-4475 4515);
DISPLAY INVISIBLE (-4475 4515);
FORCEPROP 2 LAST CDS_LIB pure_quanta
J 2
(-4250 4675);
DISPLAY INVISIBLE (-4250 4675);
FORCEPROP 2 LAST SEC_TYPE 
J 0
(-4025 5150);
DISPLAY 0.680851 (-4025 5150);
DISPLAY INVISIBLE (-4025 5150);
FORCEPROP 1 LAST PATH I80
J 2
(-4475 4475);
DISPLAY 0.723404 (-4475 4475);
PAINT GREEN (-4475 4475);
DISPLAY INVISIBLE (-4475 4475);
FORCEPROP 1 LAST PART_NUMBER AL080929000
J 2
(-4025 4942);
DISPLAY 0.723404 (-4025 4942);
PAINT GREEN (-4025 4942);
DISPLAY INVISIBLE (-4025 4942);
FORCEADD UNIVERSAL_POWER..1
R 2
(-4825 4950);
FORCEPROP 3 LASTPIN (-4825 4900) SIG_NAME P3V3_OCP_SFF_R\g
J 0
(-4815 4910);
DISPLAY 0.659574 (-4815 4910);
PAINT MONO (-4815 4910);
DISPLAY INVISIBLE (-4815 4910);
FORCEPROP 1 LAST HDL_POWER P3V3_OCP_SFF_R
J 1
(-4825 5000);
DISPLAY 0.723404 (-4825 5000);
PAINT GREEN (-4825 5000);
FORCEPROP 2 LAST CDS_LIB pure_quanta_power
J 0
(-4825 4950);
DISPLAY INVISIBLE (-4825 4950);
FORCEPROP 1 LAST PATH I81
J 2
(-4875 4975);
DISPLAY 0.872340 (-4875 4975);
PAINT AQUA (-4875 4975);
DISPLAY INVISIBLE (-4875 4975);
FORCEADD UNIVERSAL_GND..1
(-3700 4675);
FORCEPROP 3 LASTPIN (-3700 4725) SIG_NAME GND\g
J 0
(-3690 4735);
DISPLAY 0.659574 (-3690 4735);
PAINT MONO (-3690 4735);
DISPLAY INVISIBLE (-3690 4735);
FORCEPROP 2 LAST CDS_LIB pure_quanta_power
J 0
(-3700 4675);
DISPLAY INVISIBLE (-3700 4675);
FORCEPROP 1 LAST HDL_POWER GND
J 1
(-3675 4600);
DISPLAY 0.872340 (-3675 4600);
PAINT GREEN (-3675 4600);
DISPLAY INVISIBLE (-3675 4600);
FORCEPROP 1 LAST PATH I82
J 0
(-3625 4675);
DISPLAY 0.872340 (-3625 4675);
PAINT AQUA (-3625 4675);
DISPLAY INVISIBLE (-3625 4675);
FORCEADD UNIVERSAL_GND..1
(-3175 4025);
FORCEPROP 3 LASTPIN (-3175 4075) SIG_NAME GND\g
J 0
(-3165 4085);
DISPLAY 0.659574 (-3165 4085);
PAINT MONO (-3165 4085);
DISPLAY INVISIBLE (-3165 4085);
FORCEPROP 2 LAST CDS_LIB pure_quanta_power
J 0
(-3175 4025);
DISPLAY INVISIBLE (-3175 4025);
FORCEPROP 1 LAST HDL_POWER GND
J 1
(-3150 3950);
DISPLAY 0.872340 (-3150 3950);
PAINT GREEN (-3150 3950);
DISPLAY INVISIBLE (-3150 3950);
FORCEPROP 1 LAST PATH I83
J 0
(-3100 4025);
DISPLAY 0.872340 (-3100 4025);
PAINT AQUA (-3100 4025);
DISPLAY INVISIBLE (-3100 4025);
FORCEADD Q_RES..2
(-3175 4300);
FORCEPROP 1 LAST LOCATION R8093
J 0
(-3130 4425);
DISPLAY 0.978723 (-3130 4425);
FORCEPROP 0 LAST $SEC 1
J 0
(-3125 4475);
DISPLAY 0.680851 (-3125 4475);
PAINT MONO (-3125 4475);
DISPLAY INVISIBLE (-3125 4475);
FORCEPROP 0 LAST CDS_SEC 1
J 0
(-3125 4475);
DISPLAY 0.680851 (-3125 4475);
DISPLAY INVISIBLE (-3125 4475);
FORCEPROP 1 LASTPIN (-3175 4400) $PN 1
J 0
(-3170 4362);
DISPLAY 0.787234 (-3170 4362);
PAINT MONO (-3170 4362);
FORCEPROP 1 LASTPIN (-3175 4200) $PN 2
J 0
(-3170 4210);
DISPLAY 0.787234 (-3170 4210);
PAINT MONO (-3170 4210);
FORCEPROP 1 LAST VALUE 100K
J 0
(-3130 4375);
DISPLAY 0.978723 (-3130 4375);
FORCEPROP 1 LAST TOLERANCE 1%
J 0
(-3130 4325);
DISPLAY 0.978723 (-3130 4325);
FORCEPROP 1 LAST PACK_TYPE 0402LF
J 0
(-3135 4125);
DISPLAY 0.978723 (-3135 4125);
FORCEPROP 1 LAST MATERIAL CHIP
J 0
(-3135 4225);
DISPLAY 0.978723 (-3135 4225);
PAINT RED (-3135 4225);
FORCEPROP 1 LAST WATTAGE 1/16W
J 0
(-3135 4275);
DISPLAY 0.978723 (-3135 4275);
FORCEPROP 2 LAST CDS_LIB pure_quanta
J 0
(-3175 4300);
DISPLAY INVISIBLE (-3175 4300);
FORCEPROP 1 LAST PATH I84
J 0
(-3125 4475);
DISPLAY 0.978723 (-3125 4475);
PAINT WHITE (-3125 4475);
DISPLAY INVISIBLE (-3125 4475);
FORCEPROP 1 LAST PART_NUMBER CS41002FB09
J 0
(-3135 4175);
DISPLAY 0.978723 (-3135 4175);
DISPLAY INVISIBLE (-3135 4175);
FORCEADD Q_RES..1
(-2650 4575);
FORCEPROP 1 LAST LOCATION R8094
J 0
(-2875 4575);
DISPLAY 0.787234 (-2875 4575);
FORCEPROP 2 LAST SEC 1
J 0
(-2700 4775);
DISPLAY 0.680851 (-2700 4775);
PAINT MONO (-2700 4775);
DISPLAY INVISIBLE (-2700 4775);
FORCEPROP 1 LASTPIN (-2750 4575) $PN 1
J 0
(-2738 4587);
DISPLAY 0.787234 (-2738 4587);
PAINT MONO (-2738 4587);
FORCEPROP 1 LASTPIN (-2550 4575) $PN 2
J 0
(-2588 4587);
DISPLAY 0.787234 (-2588 4587);
PAINT MONO (-2588 4587);
FORCEPROP 1 LAST PACK_TYPE 0402LF
J 0
(-2400 4575);
DISPLAY 0.510638 (-2400 4575);
FORCEPROP 1 LAST VALUE 0
J 2
(-2500 4575);
DISPLAY 0.510638 (-2500 4575);
FORCEPROP 1 LAST MATERIAL CHIP
J 0
(-2725 4500);
DISPLAY 0.510638 (-2725 4500);
PAINT RED (-2725 4500);
FORCEPROP 1 LAST WATTAGE 1/16W
J 2
(-2475 4500);
DISPLAY 0.510638 (-2475 4500);
FORCEPROP 1 LAST TOLERANCE 5%
J 0
(-2475 4575);
DISPLAY 0.510638 (-2475 4575);
FORCEPROP 2 LAST CDS_LIB pure_quanta
J 0
(-2650 4575);
DISPLAY INVISIBLE (-2650 4575);
FORCEPROP 2 LAST SEC_TYPE 0402LF
J 0
(-2700 4775);
DISPLAY 0.680851 (-2700 4775);
DISPLAY INVISIBLE (-2700 4775);
FORCEPROP 1 LAST PATH I85
J 0
(-2700 4725);
DISPLAY 0.978723 (-2700 4725);
PAINT WHITE (-2700 4725);
DISPLAY INVISIBLE (-2700 4725);
FORCEPROP 1 LAST PART_NUMBER CS00002JB13
J 0
(-2725 4525);
DISPLAY 0.510638 (-2725 4525);
DISPLAY INVISIBLE (-2725 4525);
FORCEADD OFFPAGE..2
(-1450 4575);
PAINT AQUA (-1450 4575);
FORCEPROP 2 LAST $XR1 136 
J 0
(-1141 4575);
DISPLAY 0.638298 (-1141 4575);
PAINT MONO (-1141 4575);
FORCEPROP 2 LAST $XR0 134 
J 0
(-1261 4575);
DISPLAY 0.638298 (-1261 4575);
PAINT MONO (-1261 4575);
FORCEPROP 2 LAST CDS_LIB standard
J 0
(-1450 4575);
DISPLAY INVISIBLE (-1450 4575);
FORCEPROP 1 LAST OFFPAGE TRUE
J 0
(-1125 4450);
DISPLAY 0.872340 (-1125 4450);
PAINT AQUA (-1125 4450);
DISPLAY INVISIBLE (-1125 4450);
FORCEPROP 1 LAST COMMENT_BODY TRUE
J 0
(-1495 4480);
DISPLAY 0.872340 (-1495 4480);
PAINT GREEN (-1495 4480);
DISPLAY INVISIBLE (-1495 4480);
FORCEPROP 2 LAST PATH I86
J 0
(-1125 4625);
DISPLAY 0.680851 (-1125 4625);
DISPLAY INVISIBLE (-1125 4625);
FORCEADD UNIVERSAL_POWER..1
R 2
(-3175 5150);
FORCEPROP 3 LASTPIN (-3175 5100) SIG_NAME P3V3_OCP_SFF_R\g
J 0
(-3165 5110);
DISPLAY 0.659574 (-3165 5110);
PAINT MONO (-3165 5110);
DISPLAY INVISIBLE (-3165 5110);
FORCEPROP 1 LAST HDL_POWER P3V3_OCP_SFF_R
J 1
(-3175 5200);
DISPLAY 0.723404 (-3175 5200);
PAINT GREEN (-3175 5200);
FORCEPROP 2 LAST CDS_LIB pure_quanta_power
J 0
(-3175 5150);
DISPLAY INVISIBLE (-3175 5150);
FORCEPROP 1 LAST PATH I87
J 2
(-3225 5175);
DISPLAY 0.872340 (-3225 5175);
PAINT AQUA (-3225 5175);
DISPLAY INVISIBLE (-3225 5175);
FORCEADD Q_RES..2
R 2
(-3175 4900);
FORCEPROP 1 LAST LOCATION R8092
J 2
(-3220 5025);
DISPLAY 0.787234 (-3220 5025);
FORCEPROP 0 LAST $SEC 1
J 2
(-3225 5075);
DISPLAY 0.680851 (-3225 5075);
PAINT MONO (-3225 5075);
DISPLAY INVISIBLE (-3225 5075);
FORCEPROP 0 LAST CDS_SEC 1
J 2
(-3225 5075);
DISPLAY 0.680851 (-3225 5075);
DISPLAY INVISIBLE (-3225 5075);
FORCEPROP 1 LASTPIN (-3175 5000) $PN 1
J 2
(-3180 4962);
DISPLAY 0.787234 (-3180 4962);
PAINT MONO (-3180 4962);
FORCEPROP 1 LASTPIN (-3175 4800) $PN 2
J 2
(-3180 4810);
DISPLAY 0.787234 (-3180 4810);
PAINT MONO (-3180 4810);
FORCEPROP 1 LAST VALUE 10K
J 2
(-3220 4975);
DISPLAY 0.787234 (-3220 4975);
FORCEPROP 1 LAST PACK_TYPE 0402LF
J 2
(-3215 4725);
DISPLAY 0.787234 (-3215 4725);
FORCEPROP 1 LAST WATTAGE 1/16W
J 2
(-3215 4875);
DISPLAY 0.787234 (-3215 4875);
FORCEPROP 1 LAST MATERIAL EMPTY
J 2
(-3215 4825);
DISPLAY 0.787234 (-3215 4825);
PAINT RED (-3215 4825);
FORCEPROP 1 LAST TOLERANCE 5%
J 2
(-3220 4925);
DISPLAY 0.787234 (-3220 4925);
FORCEPROP 2 LAST CDS_LIB pure_quanta
J 2
(-3175 4900);
DISPLAY INVISIBLE (-3175 4900);
FORCEPROP 1 LAST PATH I90
J 2
(-3225 5075);
DISPLAY 0.978723 (-3225 5075);
PAINT WHITE (-3225 5075);
DISPLAY INVISIBLE (-3225 5075);
FORCEPROP 1 LAST PART_NUMBER CS31002JB08
J 2
(-3215 4775);
DISPLAY 0.787234 (-3215 4775);
DISPLAY INVISIBLE (-3215 4775);
FORCEADD 74LVC1G08W57..1
(-3900 6375);
FORCEPROP 1 LAST LOCATION U9050
J 0
(-4119 6831);
DISPLAY 0.723404 (-4119 6831);
PAINT GREEN (-4119 6831);
FORCEPROP 0 LAST $SEC 1
J 0
(-4100 6875);
DISPLAY 0.680851 (-4100 6875);
PAINT MONO (-4100 6875);
DISPLAY INVISIBLE (-4100 6875);
FORCEPROP 0 LAST CDS_SEC 1
J 0
(-4100 6875);
DISPLAY 0.680851 (-4100 6875);
DISPLAY INVISIBLE (-4100 6875);
FORCEPROP 0 LASTPIN (-4200 6475) $PN 1
J 2
(-4210 6485);
DISPLAY 0.680851 (-4210 6485);
PAINT MONO (-4210 6485);
FORCEPROP 0 LASTPIN (-4200 6375) $PN 2
J 2
(-4210 6385);
DISPLAY 0.680851 (-4210 6385);
PAINT MONO (-4210 6385);
FORCEPROP 0 LASTPIN (-4200 6275) $PN 3
J 2
(-4210 6285);
DISPLAY 0.680851 (-4210 6285);
PAINT MONO (-4210 6285);
FORCEPROP 0 LASTPIN (-3600 6475) $PN 5
J 0
(-3590 6485);
DISPLAY 0.680851 (-3590 6485);
PAINT MONO (-3590 6485);
FORCEPROP 0 LASTPIN (-3600 6325) $PN 4
J 0
(-3590 6335);
DISPLAY 0.680851 (-3590 6335);
PAINT MONO (-3590 6335);
FORCEPROP 1 LAST MATERIAL IC
J 0
(-4119 6557);
DISPLAY 0.723404 (-4119 6557);
PAINT GREEN (-4119 6557);
FORCEPROP 2 LAST PART_TYPE SMLF
J 0
(-4125 6725);
DISPLAY 0.808511 (-4125 6725);
FORCEPROP 2 LAST VALUE 74LVC1G08W5-7
J 0
(-4125 6675);
DISPLAY 0.808511 (-4125 6675);
FORCEPROP 2 LAST CDS_LIB pure_quanta
J 0
(-3900 6375);
DISPLAY INVISIBLE (-3900 6375);
FORCEPROP 1 LAST CDS_LMAN_SYM_OUTLINE -150,150,150,-150
J 0
(-3900 6375);
DISPLAY 0.468085 (-3900 6375);
PAINT GREEN (-3900 6375);
DISPLAY INVISIBLE (-3900 6375);
FORCEPROP 1 LAST NEEDS_NO_SIZE TRUE
J 0
(-3900 6375);
DISPLAY 0.723404 (-3900 6375);
PAINT GREEN (-3900 6375);
DISPLAY INVISIBLE (-3900 6375);
FORCEPROP 1 LAST PATH I91
J 0
(-3900 6375);
DISPLAY 0.723404 (-3900 6375);
PAINT GREEN (-3900 6375);
DISPLAY INVISIBLE (-3900 6375);
FORCEPROP 1 LAST PART_NUMBER AL1G0008020
J 0
(-4125 6625);
DISPLAY 0.723404 (-4125 6625);
PAINT GREEN (-4125 6625);
DISPLAY INVISIBLE (-4125 6625);
FORCEADD UNIVERSAL_GND..1
(-4250 6050);
FORCEPROP 3 LASTPIN (-4250 6100) SIG_NAME GND\g
J 0
(-4240 6110);
DISPLAY 0.659574 (-4240 6110);
PAINT MONO (-4240 6110);
DISPLAY INVISIBLE (-4240 6110);
FORCEPROP 2 LAST CDS_LIB pure_quanta_power
J 0
(-4250 6050);
DISPLAY INVISIBLE (-4250 6050);
FORCEPROP 1 LAST HDL_POWER GND
J 1
(-4225 5975);
DISPLAY 0.872340 (-4225 5975);
PAINT GREEN (-4225 5975);
DISPLAY INVISIBLE (-4225 5975);
FORCEPROP 1 LAST PATH I92
J 0
(-4175 6050);
DISPLAY 0.872340 (-4175 6050);
PAINT AQUA (-4175 6050);
DISPLAY INVISIBLE (-4175 6050);
FORCEADD UNIVERSAL_POWER..1
R 2
(-3475 6875);
FORCEPROP 3 LASTPIN (-3475 6825) SIG_NAME P3V3_AUX\g
J 0
(-3465 6835);
DISPLAY 0.659574 (-3465 6835);
PAINT MONO (-3465 6835);
DISPLAY INVISIBLE (-3465 6835);
FORCEPROP 1 LAST HDL_POWER P3V3_AUX
J 1
(-3475 6925);
DISPLAY 0.723404 (-3475 6925);
PAINT GREEN (-3475 6925);
FORCEPROP 2 LAST CDS_LIB pure_quanta_power
J 0
(-3475 6875);
DISPLAY INVISIBLE (-3475 6875);
FORCEPROP 1 LAST PATH I93
J 2
(-3525 6900);
DISPLAY 0.872340 (-3525 6900);
PAINT AQUA (-3525 6900);
DISPLAY INVISIBLE (-3525 6900);
FORCEADD Q_CAP..1
(-3475 6575);
FORCEPROP 1 LAST LOCATION C9050
J 0
(-3425 6700);
DISPLAY 0.638298 (-3425 6700);
FORCEPROP 0 LAST $SEC 1
J 0
(-3425 6750);
DISPLAY 0.680851 (-3425 6750);
PAINT MONO (-3425 6750);
DISPLAY INVISIBLE (-3425 6750);
FORCEPROP 0 LAST CDS_SEC 1
J 0
(-3425 6750);
DISPLAY 0.680851 (-3425 6750);
DISPLAY INVISIBLE (-3425 6750);
FORCEPROP 1 LASTPIN (-3475 6675) $PN 1
J 0
(-3465 6655);
DISPLAY 0.787234 (-3465 6655);
PAINT MONO (-3465 6655);
FORCEPROP 1 LASTPIN (-3475 6475) $PN 2
J 0
(-3465 6455);
DISPLAY 0.787234 (-3465 6455);
PAINT MONO (-3465 6455);
FORCEPROP 1 LAST TOLERANCE 10%
J 0
(-3425 6550);
DISPLAY 0.638298 (-3425 6550);
FORCEPROP 1 LAST MATERIAL X7R
J 0
(-3425 6500);
DISPLAY 0.638298 (-3425 6500);
PAINT RED (-3425 6500);
FORCEPROP 1 LAST PACK_TYPE 0402
J 0
(-3425 6400);
DISPLAY 0.638298 (-3425 6400);
FORCEPROP 1 LAST VALUE 0.1UF
J 0
(-3425 6650);
DISPLAY 0.638298 (-3425 6650);
FORCEPROP 1 LAST VOLTAGE 25V
J 0
(-3425 6600);
DISPLAY 0.638298 (-3425 6600);
FORCEPROP 2 LAST CDS_LIB pure_quanta
J 0
(-3475 6575);
DISPLAY INVISIBLE (-3475 6575);
FORCEPROP 1 LAST PATH I94
J 0
(-3425 6725);
DISPLAY 0.978723 (-3425 6725);
PAINT WHITE (-3425 6725);
DISPLAY INVISIBLE (-3425 6725);
FORCEPROP 1 LAST PART_NUMBER CH4104K1B00
J 0
(-3425 6450);
DISPLAY 0.638298 (-3425 6450);
DISPLAY INVISIBLE (-3425 6450);
FORCEADD UNIVERSAL_GND..1
(-3475 6375);
FORCEPROP 3 LASTPIN (-3475 6425) SIG_NAME GND\g
J 0
(-3465 6435);
DISPLAY 0.659574 (-3465 6435);
PAINT MONO (-3465 6435);
DISPLAY INVISIBLE (-3465 6435);
FORCEPROP 2 LAST CDS_LIB pure_quanta_power
J 0
(-3475 6375);
DISPLAY INVISIBLE (-3475 6375);
FORCEPROP 1 LAST HDL_POWER GND
J 1
(-3450 6300);
DISPLAY 0.872340 (-3450 6300);
PAINT GREEN (-3450 6300);
DISPLAY INVISIBLE (-3450 6300);
FORCEPROP 1 LAST PATH I95
J 0
(-3400 6375);
DISPLAY 0.872340 (-3400 6375);
PAINT AQUA (-3400 6375);
DISPLAY INVISIBLE (-3400 6375);
FORCEADD Q_RES..1
(-3975 5925);
FORCEPROP 1 LAST LOCATION R1509
J 0
(-4025 5975);
DISPLAY 0.978723 (-4025 5975);
PAINT SKYBLUE (-4025 5975);
FORCEPROP 0 LAST $SEC 1
J 0
(-4025 6025);
DISPLAY 0.680851 (-4025 6025);
PAINT MONO (-4025 6025);
DISPLAY INVISIBLE (-4025 6025);
FORCEPROP 0 LAST CDS_SEC 1
J 0
(-4025 6025);
DISPLAY 0.680851 (-4025 6025);
DISPLAY INVISIBLE (-4025 6025);
FORCEPROP 1 LASTPIN (-4075 5925) $PN 1
J 0
(-4063 5937);
DISPLAY 0.787234 (-4063 5937);
PAINT MONO (-4063 5937);
FORCEPROP 1 LASTPIN (-3875 5925) $PN 2
J 0
(-3913 5937);
DISPLAY 0.787234 (-3913 5937);
PAINT MONO (-3913 5937);
FORCEPROP 1 LAST TOLERANCE 5%
J 0
(-3800 5925);
DISPLAY 0.510638 (-3800 5925);
FORCEPROP 1 LAST VALUE 0
J 2
(-3825 5925);
DISPLAY 0.510638 (-3825 5925);
FORCEPROP 1 LAST PACK_TYPE 0402LF
J 0
(-3725 5925);
DISPLAY 0.510638 (-3725 5925);
FORCEPROP 1 LAST WATTAGE 1/16W
J 2
(-3775 5850);
DISPLAY 0.510638 (-3775 5850);
FORCEPROP 1 LAST MATERIAL CHIP
J 0
(-4050 5850);
DISPLAY 0.510638 (-4050 5850);
PAINT RED (-4050 5850);
FORCEPROP 2 LAST CDS_LIB pure_quanta
J 0
(-3975 5925);
DISPLAY INVISIBLE (-3975 5925);
FORCEPROP 1 LAST PATH I96
J 0
(-4025 6075);
DISPLAY 0.978723 (-4025 6075);
PAINT WHITE (-4025 6075);
DISPLAY INVISIBLE (-4025 6075);
FORCEPROP 1 LAST PART_NUMBER CS00002JB13
J 0
(-4050 5875);
DISPLAY 0.510638 (-4050 5875);
DISPLAY INVISIBLE (-4050 5875);
FORCEADD OFFPAGE..1
(-5075 5925);
PAINT AQUA (-5075 5925);
FORCEPROP 2 LAST $XR3 248 
J 0
(-5357 5853);
DISPLAY 0.638298 (-5357 5853);
PAINT MONO (-5357 5853);
FORCEPROP 2 LAST $XR2 136 
J 0
(-5357 5961);
DISPLAY 0.638298 (-5357 5961);
PAINT MONO (-5357 5961);
FORCEPROP 2 LAST $XR1 135 
J 0
(-5357 5889);
DISPLAY 0.638298 (-5357 5889);
PAINT MONO (-5357 5889);
FORCEPROP 2 LAST $XR0 134 
J 0
(-5357 5925);
DISPLAY 0.638298 (-5357 5925);
PAINT MONO (-5357 5925);
FORCEPROP 2 LAST CDS_LIB standard
J 0
(-5075 5925);
DISPLAY INVISIBLE (-5075 5925);
FORCEPROP 1 LAST OFFPAGE TRUE
J 0
(-4750 5800);
DISPLAY 0.872340 (-4750 5800);
PAINT AQUA (-4750 5800);
DISPLAY INVISIBLE (-4750 5800);
FORCEPROP 1 LAST COMMENT_BODY TRUE
J 0
(-4950 5825);
DISPLAY 0.872340 (-4950 5825);
PAINT GREEN (-4950 5825);
DISPLAY INVISIBLE (-4950 5825);
FORCEPROP 2 LAST PATH I97
J 0
(-5025 6000);
DISPLAY 0.680851 (-5025 6000);
DISPLAY INVISIBLE (-5025 6000);
FORCEADD OFFPAGE..2
(-2525 5925);
PAINT AQUA (-2525 5925);
FORCEPROP 2 LAST $XR0 136 
J 0
(-2336 5925);
DISPLAY 0.638298 (-2336 5925);
PAINT MONO (-2336 5925);
FORCEPROP 2 LAST CDS_LIB standard
J 0
(-2525 5925);
DISPLAY INVISIBLE (-2525 5925);
FORCEPROP 1 LAST OFFPAGE TRUE
J 0
(-2200 5800);
DISPLAY 0.872340 (-2200 5800);
PAINT AQUA (-2200 5800);
DISPLAY INVISIBLE (-2200 5800);
FORCEPROP 1 LAST COMMENT_BODY TRUE
J 0
(-2570 5830);
DISPLAY 0.872340 (-2570 5830);
PAINT GREEN (-2570 5830);
DISPLAY INVISIBLE (-2570 5830);
FORCEPROP 2 LAST PATH I98
J 0
(-2350 6000);
DISPLAY 0.680851 (-2350 6000);
DISPLAY INVISIBLE (-2350 6000);
FORCEADD OFFPAGE..1
(-5000 6375);
PAINT AQUA (-5000 6375);
FORCEPROP 2 LAST $XR0 136 
J 0
(-5252 6375);
DISPLAY 0.638298 (-5252 6375);
PAINT MONO (-5252 6375);
FORCEPROP 2 LAST CDS_LIB standard
J 0
(-5000 6375);
DISPLAY INVISIBLE (-5000 6375);
FORCEPROP 1 LAST OFFPAGE TRUE
J 0
(-4675 6250);
DISPLAY 0.872340 (-4675 6250);
PAINT AQUA (-4675 6250);
DISPLAY INVISIBLE (-4675 6250);
FORCEPROP 1 LAST COMMENT_BODY TRUE
J 0
(-4875 6275);
DISPLAY 0.872340 (-4875 6275);
PAINT GREEN (-4875 6275);
DISPLAY INVISIBLE (-4875 6275);
FORCEPROP 2 LAST PATH I99
J 0
(-4950 6450);
DISPLAY 0.680851 (-4950 6450);
DISPLAY INVISIBLE (-4950 6450);
FORCEADD DNS..2
(-3250 4900);
PAINT RED (-3250 4900);
FORCEPROP 2 LAST CDS_LIB mstr_misc
J 0
(-3250 4900);
DISPLAY INVISIBLE (-3250 4900);
FORCEPROP 1 LAST COMMENT_BODY TRUE
R 1
J 0
(-3175 4675);
DISPLAY 0.872340 (-3175 4675);
PAINT GREEN (-3175 4675);
DISPLAY INVISIBLE (-3175 4675);
FORCEADD DESIGN_NOTE..1
(-475 4950);
FORCEPROP 0 LAST L1 FM_PLD_OCP_SFF_AUX_PWR_EN SET TO HIGH BY DEFAULT
J 0
(-675 4825);
DISPLAY 0.808511 (-675 4825);
PAINT SKYBLUE (-675 4825);
FORCEPROP 2 LAST CDS_LIB pure_quanta_power
J 0
(-475 4950);
DISPLAY INVISIBLE (-475 4950);
FORCEPROP 0 LAST L2 UART_2 BMC TO MB (BMC HOST)
J 0
(-675 4750);
DISPLAY 0.808511 (-675 4750);
PAINT SKYBLUE (-675 4750);
DISPLAY INVISIBLE (-675 4750);
FORCEPROP 1 LAST COMMENT_BODY TRUE
J 0
(-450 5050);
DISPLAY 0.978723 (-450 5050);
DISPLAY INVISIBLE (-450 5050);
FORCEADD QUANTA_TITLE_BLOCK_C..1
(3975 3800);
FORCEPROP 0 LAST CDS_CON_LAST_MODIFIED Thu Sep 14 16:13:10 2023
J 0
(2090 3815);
PAINT MONO (2090 3815);
DISPLAY INVISIBLE (2090 3815);
FORCEPROP 2 LAST CUSTOM_TXT_CDS <XR_PAGE_TITLE>
J 0
(-3915 9050);
DISPLAY 0.638298 (-3915 9050);
PAINT PINK (-3915 9050);
DISPLAY INVISIBLE (-3915 9050);
FORCEPROP 2 LAST CUSTOM_TXT_CDS <CON_LAST_MODIFIED>
J 0
(2090 3815);
DISPLAY 0.978723 (2090 3815);
FORCEPROP 2 LAST CUSTOM_TXT_CDS <NAME_1>
J 0
(800 3975);
FORCEPROP 2 LAST CUSTOM_TXT_CDS <Q_NUMBER>
J 0
(2572 3903);
DISPLAY 1.212766 (2572 3903);
FORCEPROP 2 LAST CUSTOM_TXT_CDS <Q_REV>
J 0
(3791 3903);
DISPLAY 1.212766 (3791 3903);
FORCEPROP 2 LAST CUSTOM_TXT_CDS <Q_PROJ>
J 0
(1593 3902);
DISPLAY 1.212766 (1593 3902);
FORCEPROP 2 LAST CUSTOM_TXT_CDS <NAME_2>
J 0
(800 3850);
FORCEPROP 2 LAST CUSTOM_TXT_CDS <CON_PAGE_NUM> OF <CON_TOTAL_PAGES>
J 0
(3529 3818);
DISPLAY 0.978723 (3529 3818);
FORCEPROP 1 LAST Q_TITLE SFF_OCP3.0 HSC(3/3)
J 0
(-5291 3826);
DISPLAY 2.446809 (-5291 3826);
PAINT GREEN (-5291 3826);
FORCEPROP 2 LAST PAGE_BORDER TRUE
J 0
(-3915 9050);
DISPLAY 0.638298 (-3915 9050);
PAINT PINK (-3915 9050);
DISPLAY INVISIBLE (-3915 9050);
FORCEPROP 1 LAST CDS_LMAN_SYM_OUTLINE -9475,6775,100,-125
J 0
(3975 3800);
DISPLAY 0.468085 (3975 3800);
PAINT GREEN (3975 3800);
DISPLAY INVISIBLE (3975 3800);
FORCEPROP 2 LAST CDS_LIB pure_quanta
J 0
(3975 3800);
PAINT MONO (3975 3800);
DISPLAY INVISIBLE (3975 3800);
FORCEPROP 2 LAST CDS_XR_PAGE_TITLE CR-136 : @T6G_MB_LIB.T6G(SCH_1):PAGE136
J 0
(-3915 9050);
DISPLAY 0.638298 (-3915 9050);
PAINT PINK (-3915 9050);
DISPLAY INVISIBLE (-3915 9050);
FORCEPROP 1 LAST Q_DEPT BU9
J 1
(212 3849);
DISPLAY 1.957447 (212 3849);
PAINT GREEN (212 3849);
DISPLAY INVISIBLE (212 3849);
FORCEPROP 1 LAST COMMENT_BODY TRUE
J 0
(3987 3787);
DISPLAY 0.978723 (3987 3787);
PAINT GREEN (3987 3787);
DISPLAY INVISIBLE (3987 3787);
FORCEADD DNS..2
(825 4550);
PAINT RED (825 4550);
FORCEPROP 2 LAST CDS_LIB mstr_misc
J 0
(825 4550);
DISPLAY INVISIBLE (825 4550);
FORCEPROP 1 LAST COMMENT_BODY TRUE
R 1
J 0
(900 4325);
DISPLAY 0.872340 (900 4325);
PAINT GREEN (900 4325);
DISPLAY INVISIBLE (900 4325);
FORCEADD DNS..2
(-2125 9350);
PAINT RED (-2125 9350);
FORCEPROP 2 LAST CDS_LIB mstr_misc
J 0
(-2125 9350);
DISPLAY INVISIBLE (-2125 9350);
FORCEPROP 1 LAST COMMENT_BODY TRUE
R 1
J 0
(-2050 9125);
DISPLAY 0.872340 (-2050 9125);
PAINT GREEN (-2050 9125);
DISPLAY INVISIBLE (-2050 9125);
FORCEADD DNS..2
(2775 5825);
PAINT RED (2775 5825);
FORCEPROP 2 LAST CDS_LIB mstr_misc
J 0
(2775 5825);
DISPLAY INVISIBLE (2775 5825);
FORCEPROP 1 LAST COMMENT_BODY TRUE
R 1
J 0
(2850 5600);
DISPLAY 0.872340 (2850 5600);
PAINT GREEN (2850 5600);
DISPLAY INVISIBLE (2850 5600);
FORCEADD DNS..2
(875 6100);
PAINT RED (875 6100);
FORCEPROP 2 LAST CDS_LIB mstr_misc
J 0
(875 6100);
DISPLAY INVISIBLE (875 6100);
FORCEPROP 1 LAST COMMENT_BODY TRUE
R 1
J 0
(950 5875);
DISPLAY 0.872340 (950 5875);
PAINT GREEN (950 5875);
DISPLAY INVISIBLE (950 5875);
FORCEADD DNS..2
(-1950 6575);
PAINT RED (-1950 6575);
FORCEPROP 2 LAST CDS_LIB mstr_misc
J 0
(-1950 6575);
DISPLAY INVISIBLE (-1950 6575);
FORCEPROP 1 LAST COMMENT_BODY TRUE
R 1
J 0
(-1875 6350);
DISPLAY 0.872340 (-1875 6350);
PAINT GREEN (-1875 6350);
DISPLAY INVISIBLE (-1875 6350);
WIRE 16 -1 (150 5275)(150 5150);
WIRE 16 -1 (150 5275)(225 5275);
WIRE 16 -1 (-50 5600)(-50 5550);
WIRE 16 -1 (150 6500)(200 6500);
WIRE 16 -1 (150 6500)(150 6275);
WIRE 16 -1 (1050 6775)(1050 6725);
WIRE 16 -1 (-3875 8750)(-3875 8450);
WIRE 16 -1 (-3875 9600)(-3875 9850);
WIRE 16 -1 (-1625 5750)(-1625 5925);
WIRE 16 -1 (-150 9450)(-150 9300);
WIRE 16 -1 (-1225 10075)(-1225 9825);
WIRE 16 -1 (-3100 7775)(-3100 7700);
WIRE 16 -1 (-875 8000)(-875 7900);
WIRE 16 -1 (2475 8775)(2475 8675);
WIRE 16 -1 (175 8550)(175 8475);
WIRE 16 -1 (2700 5950)(2700 6050);
WIRE 16 -1 (-4825 4325)(-4825 4150);
WIRE 16 -1 (-3875 4775)(-3700 4775);
WIRE 16 -1 (-3700 4775)(-3700 4725);
WIRE 16 -1 (-3175 4200)(-3175 4075);
WIRE 16 -1 (-3175 5000)(-3175 5100);
WIRE 16 -1 (-4200 6275)(-4250 6275);
WIRE 16 -1 (-4250 6275)(-4250 6100);
WIRE 16 -1 (-3475 6475)(-3475 6425);
WIRE 16 -1 (-1375 6600)(-1375 6325);
WIRE 16 -1 (-1375 6600)(-1100 6600);
WIRE 16 -1 (-1850 6600)(-1375 6600);
FORCEPROP 2 LAST SIG_NAME OCP_V3_1_P3V3_R3_PWRGD
J 0
(-1835 6610);
DISPLAY 0.553191 (-1835 6610);
FORCEPROP 2 LASTPROP $XRERR UNIQUE?
J 0
(-2075 6610);
DISPLAY 0.638298 (-2075 6610);
PAINT MONO (-2075 6610);
DISPLAY INVISIBLE (-2075 6610);
WIRE 16 -1 (-1900 6325)(-1375 6325);
WIRE 16 -1 (-1375 6325)(-1375 5425);
WIRE 16 -1 (-1375 5425)(-1175 5425);
WIRE 16 -1 (1525 5375)(1725 5375);
WIRE 16 -1 (1525 5375)(1525 6075);
WIRE 16 -1 (1525 5375)(1525 4575);
WIRE 16 -1 (725 5375)(1525 5375);
FORCEPROP 0 LAST SIG_NAME OCP_SFF_AUX_PWR_EN_R3
J 0
(790 5410);
DISPLAY 0.680851 (790 5410);
PAINT SKYBLUE (790 5410);
FORCEPROP 2 LASTPROP $XRERR UNIQUE?
J 0
(550 5410);
DISPLAY 0.638298 (550 5410);
PAINT MONO (550 5410);
DISPLAY INVISIBLE (550 5410);
WIRE 16 -1 (1525 4575)(925 4575);
WIRE 16 -1 (1525 6075)(925 6075);
WIRE 16 -1 (-800 4575)(725 4575);
WIRE 16 -1 (-800 5325)(-800 4575);
WIRE 16 -1 (125 5325)(-800 5325);
WIRE 16 -1 (-800 5325)(-1625 5325);
FORCEPROP 2 LAST SIG_NAME FM_PLD_OCP_SFF_AUX_PWR_EN
J 0
(-810 5335);
DISPLAY 0.680851 (-810 5335);
PAINT SKYBLUE (-810 5335);
WIRE 16 -1 (-1625 5550)(-1625 5325);
WIRE 16 -1 (-1625 5325)(-1925 5325);
WIRE 16 -1 (-975 5425)(-800 5425);
FORCEPROP 0 LAST SIG_NAME HP_LVC3_OCP_V3_1_PWRGD_R1
J 0
(-785 5435);
DISPLAY 0.680851 (-785 5435);
PAINT SKYBLUE (-785 5435);
FORCEPROP 2 LASTPROP $XRERR UNIQUE?
J 0
(-1025 5435);
DISPLAY 0.638298 (-1025 5435);
PAINT MONO (-1025 5435);
DISPLAY INVISIBLE (-1025 5435);
WIRE 16 -1 (-800 5425)(125 5425);
WIRE 16 -1 (-800 5425)(-800 6075);
WIRE 16 -1 (725 6075)(-800 6075);
WIRE 16 -1 (-1500 4575)(-2550 4575);
FORCEPROP 2 LAST SIG_NAME OCP_V3_1_P3V3_PWRGD
J 0
(-2210 4585);
DISPLAY 0.680851 (-2210 4585);
WIRE 16 -1 (2150 6550)(3100 6550);
FORCEPROP 2 LAST SIG_NAME RST_PERST_OCP_SFF_BUF_N
J 0
(2325 6560);
DISPLAY 0.680851 (2325 6560);
PAINT SKYBLUE (2325 6560);
WIRE 16 -1 (225 5475)(125 5475);
WIRE 16 -1 (125 5475)(125 5825);
WIRE 16 -1 (-25 5825)(125 5825);
WIRE 16 -1 (-50 5825)(-25 5825);
WIRE 16 -1 (-25 5825)(-25 5875);
WIRE 16 -1 (-50 5800)(-50 5825);
WIRE 16 -1 (-1850 6700)(-1100 6700);
FORCEPROP 2 LAST SIG_NAME RST_PERST_OCP_SFF_N
J 0
(-1835 6710);
DISPLAY 0.680851 (-1835 6710);
PAINT SKYBLUE (-1835 6710);
WIRE 16 -1 (800 6550)(1950 6550);
FORCEPROP 2 LAST SIG_NAME RST_PERST_OCP_SFF_BUF_R_N
J 0
(965 6575);
DISPLAY 0.680851 (965 6575);
PAINT SKYBLUE (965 6575);
FORCEPROP 2 LASTPROP $XRERR UNIQUE?
J 0
(725 6575);
DISPLAY 0.638298 (725 6575);
PAINT MONO (725 6575);
DISPLAY INVISIBLE (725 6575);
WIRE 16 -1 (-900 6600)(200 6600);
FORCEPROP 0 LAST SIG_NAME HP_LVC3_OCP_V3_1_PWRGD
J 0
(-625 6610);
DISPLAY 0.680851 (-625 6610);
PAINT SKYBLUE (-625 6610);
FORCEPROP 2 LASTPROP $XRERR UNIQUE?
J 0
(-865 6610);
DISPLAY 0.638298 (-865 6610);
PAINT MONO (-865 6610);
DISPLAY INVISIBLE (-865 6610);
WIRE 16 -1 (-3600 6325)(-2100 6325);
FORCEPROP 2 LAST SIG_NAME HP_LVC3_OCP_V3_1_PWRGD_R2
J 0
(-3210 6335);
DISPLAY 0.680851 (-3210 6335);
FORCEPROP 2 LASTPROP $XRERR UNIQUE?
J 0
(-3450 6335);
DISPLAY 0.638298 (-3450 6335);
PAINT MONO (-3450 6335);
DISPLAY INVISIBLE (-3450 6335);
WIRE 16 -1 (-2625 6600)(-2050 6600);
FORCEPROP 2 LAST SIG_NAME OCP_V3_1_P3V3_PWRGD
J 0
(-2635 6610);
DISPLAY 0.553191 (-2635 6610);
PAINT SKYBLUE (-2635 6610);
WIRE 16 -1 (-1200 8225)(-550 8225);
FORCEPROP 2 LAST SIG_NAME OCP_V3_1_P3V3_PWRGD
J 0
(-1185 8235);
DISPLAY 0.680851 (-1185 8235);
WIRE 16 -1 (-4200 6475)(-4950 6475);
FORCEPROP 2 LAST SIG_NAME OCP_V3_1_P3V3_PWRGD
J 0
(-4910 6485);
DISPLAY 0.680851 (-4910 6485);
WIRE 16 -1 (-2225 9300)(-3000 9300);
FORCEPROP 2 LAST SIG_NAME P12V_OCP_SFF_EN_R
J 0
(-2935 9310);
DISPLAY 0.680851 (-2935 9310);
WIRE 16 -1 (-3875 9400)(-3875 9200);
WIRE 16 -1 (-1050 9200)(-3875 9200);
FORCEPROP 2 LAST SIG_NAME HP_LVC3_OCP_SFF_PRSNT2
J 0
(-3610 9210);
DISPLAY 0.680851 (-3610 9210);
FORCEPROP 2 LASTPROP $XRERR UNIQUE?
J 0
(-3850 9210);
DISPLAY 0.638298 (-3850 9210);
PAINT MONO (-3850 9210);
DISPLAY INVISIBLE (-3850 9210);
WIRE 16 -1 (-3875 9050)(-3875 9200);
WIRE 16 -1 (-4025 8850)(-4950 8850);
FORCEPROP 2 LAST SIG_NAME HP_LVC3_OCP_SFF_PRSNT2_N
J 0
(-4835 8860);
DISPLAY 0.680851 (-4835 8860);
WIRE 16 -1 (-3875 5925)(-2575 5925);
FORCEPROP 2 LAST SIG_NAME HP_LVC3_OCP_V3_1_P12V_R2_PWRGD
J 0
(-3535 5935);
DISPLAY 0.680851 (-3535 5935);
WIRE 16 -1 (-4825 7450)(-3900 7450);
FORCEPROP 2 LAST SIG_NAME HP_LVC3_OCP_V3_1_P12V_PWRGD
J 0
(-4785 7460);
DISPLAY 0.680851 (-4785 7460);
WIRE 16 -1 (200 6700)(-900 6700);
FORCEPROP 2 LAST SIG_NAME RST_PERST_OCP_SFF_R_N
J 0
(-625 6710);
DISPLAY 0.680851 (-625 6710);
PAINT SKYBLUE (-625 6710);
FORCEPROP 2 LASTPROP $XRERR UNIQUE?
J 0
(-865 6710);
DISPLAY 0.638298 (-865 6710);
PAINT MONO (-865 6710);
DISPLAY INVISIBLE (-865 6710);
WIRE 16 -1 (750 9150)(1800 9150);
FORCEPROP 2 LAST SIG_NAME P12V_OCP_SFF_BUF_EN_R
J 0
(1090 9160);
DISPLAY 0.680851 (1090 9160);
WIRE 16 -1 (-450 9150)(550 9150);
FORCEPROP 2 LAST SIG_NAME P12V_OCP_SFF_BUF_EN
J 0
(-285 9185);
DISPLAY 0.851064 (-285 9185);
FORCEPROP 2 LASTPROP $XRERR UNIQUE?
J 0
(-525 9185);
DISPLAY 0.638298 (-525 9185);
PAINT MONO (-525 9185);
DISPLAY INVISIBLE (-525 9185);
WIRE 16 -1 (1075 8225)(1875 8225);
FORCEPROP 2 LAST SIG_NAME OCP_V3_1_P3V3_PLD_PWRGD
J 0
(1115 8235);
DISPLAY 0.680851 (1115 8235);
FORCEPROP 2 LASTPROP $XRERR UNIQUE?
J 0
(875 8235);
DISPLAY 0.638298 (875 8235);
PAINT MONO (875 8235);
DISPLAY INVISIBLE (875 8235);
WIRE 16 -1 (2475 8475)(2475 8225);
WIRE 16 -1 (3350 8225)(2475 8225);
FORCEPROP 2 LAST SIG_NAME OCP_V3_1_P3V3_PLD_R_PWRGD
J 0
(2490 8235);
DISPLAY 0.680851 (2490 8235);
WIRE 16 -1 (2075 8225)(2475 8225);
WIRE 16 -1 (1925 5375)(2700 5375);
FORCEPROP 2 LAST SIG_NAME OCP_SFF_AUX_PWR_EN
J 0
(2100 5385);
DISPLAY 0.680851 (2100 5385);
PAINT SKYBLUE (2100 5385);
WIRE 16 -1 (2700 5750)(2700 5375);
WIRE 16 -1 (2700 5375)(2750 5375);
WIRE 16 -1 (725 8225)(-350 8225);
FORCEPROP 2 LAST SIG_NAME OCP_V3_1_P3V3_R2_PWRGD
J 0
(-10 8235);
DISPLAY 0.680851 (-10 8235);
FORCEPROP 2 LASTPROP $XRERR UNIQUE?
J 0
(-250 8235);
DISPLAY 0.638298 (-250 8235);
PAINT MONO (-250 8235);
DISPLAY INVISIBLE (-250 8235);
WIRE 16 -1 (-3875 4575)(-3175 4575);
FORCEPROP 2 LAST SIG_NAME OCP_V3_1_P3V3_R1_PWRGD
J 0
(-3785 4610);
DISPLAY 0.553191 (-3785 4610);
FORCEPROP 2 LASTPROP $XRERR UNIQUE?
J 0
(-4025 4610);
DISPLAY 0.638298 (-4025 4610);
PAINT MONO (-4025 4610);
DISPLAY INVISIBLE (-4025 4610);
WIRE 16 -1 (-2750 4575)(-3175 4575);
WIRE 16 -1 (-3175 4800)(-3175 4575);
WIRE 16 -1 (-3175 4400)(-3175 4575);
WIRE 16 -1 (900 6700)(900 7050);
WIRE 16 -1 (800 6700)(900 6700);
WIRE 16 -1 (900 7050)(1050 7050);
WIRE 16 -1 (1050 7050)(1050 7100);
WIRE 16 -1 (1050 6975)(1050 7050);
WIRE 16 -1 (-1325 9100)(-1050 9100);
WIRE 16 -1 (-1325 8875)(-1325 9100);
WIRE 16 -1 (-150 9775)(-150 9725);
WIRE 16 -1 (-150 9725)(-150 9650);
WIRE 16 -1 (-325 9725)(-150 9725);
WIRE 16 -1 (-325 9300)(-325 9725);
WIRE 16 -1 (-450 9300)(-325 9300);
WIRE 16 -1 (-3100 7975)(-3100 8100);
WIRE 16 -1 (-3100 8100)(-3075 8100);
WIRE 16 -1 (-3075 8100)(-2975 8100);
WIRE 16 -1 (-3075 8100)(-3075 8150);
WIRE 16 -1 (-2975 8100)(-2975 7550);
WIRE 16 -1 (-2975 7550)(-2550 7550);
WIRE 16 -1 (-2950 7350)(-2550 7350);
WIRE 16 -1 (-2950 7300)(-2950 7350);
WIRE 16 -1 (325 8125)(725 8125);
WIRE 16 -1 (325 8075)(325 8125);
WIRE 16 -1 (175 8750)(175 8875);
WIRE 16 -1 (175 8875)(200 8875);
WIRE 16 -1 (200 8875)(300 8875);
WIRE 16 -1 (200 8875)(200 8925);
WIRE 16 -1 (300 8875)(300 8325);
WIRE 16 -1 (300 8325)(725 8325);
WIRE 16 -1 (-4825 4900)(-4825 4675);
WIRE 16 -1 (-4825 4675)(-4625 4675);
WIRE 16 -1 (-4825 4675)(-4825 4525);
WIRE 16 -1 (-3550 6750)(-3475 6750);
WIRE 16 -1 (-3550 6750)(-3550 6475);
WIRE 16 -1 (-3475 6750)(-3475 6825);
WIRE 16 -1 (-3475 6750)(-3475 6675);
WIRE 16 -1 (-3550 6475)(-3600 6475);
WIRE 16 -1 (-1225 7450)(-875 7450);
WIRE 16 -1 (-200 7450)(-875 7450);
FORCEPROP 2 LAST SIG_NAME P12V_OCP_V3_1_PLD_PWRGD
J 0
(-835 7485);
DISPLAY 0.553191 (-835 7485);
WIRE 16 -1 (-875 7700)(-875 7450);
WIRE 16 -1 (-2550 7450)(-3700 7450);
FORCEPROP 2 LAST SIG_NAME HP_LVC3_OCP_V3_1_P12V_R_PWRGD
J 0
(-3385 7460);
DISPLAY 0.553191 (-3385 7460);
FORCEPROP 2 LASTPROP $XRERR UNIQUE?
J 0
(-3625 7460);
DISPLAY 0.638298 (-3625 7460);
PAINT MONO (-3625 7460);
DISPLAY INVISIBLE (-3625 7460);
WIRE 16 -1 (-2200 7450)(-1425 7450);
FORCEPROP 2 LAST SIG_NAME P12V_OCP_V3_1_PLD_R_PWRGD
J 0
(-2110 7460);
DISPLAY 0.553191 (-2110 7460);
FORCEPROP 2 LASTPROP $XRERR UNIQUE?
J 0
(-2350 7460);
DISPLAY 0.638298 (-2350 7460);
PAINT MONO (-2350 7460);
DISPLAY INVISIBLE (-2350 7460);
WIRE 16 -1 (-1050 9300)(-1225 9300);
WIRE 16 -1 (-1225 9625)(-1225 9300);
WIRE 16 -1 (-2025 9300)(-1225 9300);
FORCEPROP 2 LAST SIG_NAME P12V_OCP_SFF_EN_R3
J 0
(-1860 9310);
DISPLAY 0.680851 (-1860 9310);
FORCEPROP 2 LASTPROP $XRERR UNIQUE?
J 0
(-2100 9310);
DISPLAY 0.638298 (-2100 9310);
PAINT MONO (-2100 9310);
DISPLAY INVISIBLE (-2100 9310);
WIRE 16 -1 (-4075 5925)(-5025 5925);
FORCEPROP 2 LAST SIG_NAME HP_LVC3_OCP_V3_1_P12V_PWRGD
J 0
(-4985 5935);
DISPLAY 0.680851 (-4985 5935);
WIRE 16 -1 (-4200 6375)(-4950 6375);
FORCEPROP 2 LAST SIG_NAME HP_LVC3_OCP_V3_1_P12V_R2_PWRGD
J 0
(-4910 6385);
DISPLAY 0.446809 (-4910 6385);
DOT 1 (-4825 4675);
DOT 1 (-1225 9300);
DOT 1 (-800 5325);
DOT 1 (1525 5375);
DOT 1 (-25 5825);
DOT 1 (-800 5425);
DOT 1 (2475 8225);
DOT 1 (-3075 8100);
DOT 1 (-1625 5325);
DOT 1 (-3875 9200);
DOT 1 (1050 7050);
DOT 1 (-150 9725);
DOT 1 (2700 5375);
DOT 1 (-3175 4575);
DOT 1 (200 8875);
DOT 1 (-1375 6600);
DOT 1 (-3475 6750);
DOT 1 (-1375 6325);
DOT 1 (-875 7450);
FORCENOTE
FROM CPLD
(-3275 9425) 0;
DISPLAY LEFT (-3275 9425);
DISPLAY 1.021277 (-3275 9425);
FORCENOTE
OCP CARD PRSNT
(-4975 8725) 0;
DISPLAY LEFT (-4975 8725);
DISPLAY 1.021277 (-4975 8725);
FORCENOTE
OPEN DRAIN
(-2600 7200) 0;
DISPLAY LEFT (-2600 7200);
DISPLAY 1.021277 (-2600 7200);
FORCENOTE
TO OCP_HSC EN
(1150 9050) 0;
DISPLAY LEFT (1150 9050);
DISPLAY 1.021277 (1150 9050);
FORCENOTE
PUSH PULL
(-950 8950) 0;
DISPLAY LEFT (-950 8950);
DISPLAY 1.021277 (-950 8950);
FORCENOTE
PUSH PULL OUTPUT
(-4700 4350) 0;
DISPLAY LEFT (-4700 4350);
DISPLAY 1.276596 (-4700 4350);
FORCENOTE
OPEN DRAIN
(675 7975) 0;
DISPLAY LEFT (675 7975);
DISPLAY 1.021277 (675 7975);
FORCENOTE
PUSH PULL
(325 6350) 0;
DISPLAY LEFT (325 6350);
DISPLAY 1.021277 (325 6350);
FORCENOTE
PUSH PULL
(-4100 6125) 0;
DISPLAY LEFT (-4100 6125);
DISPLAY 1.021277 (-4100 6125);
FORCENOTE
P3V3_OCP_SFF PWRGD
(-2300 4325) 0;
DISPLAY LEFT (-2300 4325);
DISPLAY 1.021277 (-2300 4325);
QUIT
